G04 ================== begin FILE IDENTIFICATION RECORD ==================*
G04 Layout Name:  13130-1b.brd*
G04 Film Name:    DIF_REF_L8*
G04 File Format:  Gerber RS274X*
G04 File Origin:  Cadence Allegro 16.5-S037*
G04 Origin Date:  Thu Nov 13 18:47:02 2014*
G04 *
G04 Layer:  BOARD GEOMETRY/OUTLINE*
G04 Layer:  BOARD GEOMETRY/DIF_REF_L8*
G04 Layer:  BOARD GEOMETRY/PANEL_OUTLINE*
G04 *
G04 Offset:    (0.00 0.00)*
G04 Mirror:    No*
G04 Mode:      Positive*
G04 Rotation:  0*
G04 FullContactRelief:  No*
G04 UndefLineWidth:     6.00*
G04 ================== end FILE IDENTIFICATION RECORD ====================*
%FSLAX35Y35*MOIN*%
%IR0*IPPOS*OFA0.00000B0.00000*MIA0B0*SFA1.00000B1.00000*%
%ADD10C,.004*%
%ADD11C,.006*%
%ADD12C,.0045*%
%ADD13C,.0075*%
G75*
%LPD*%
G75*
G54D10*
G01X324564Y163384D02*
X327206D01*
G01X323000Y161820D02*
X324564Y163384D01*
G01X323000Y160558D02*
Y161820D01*
G01X319618Y157176D02*
X323000Y160558D01*
G01X319618Y156822D02*
Y157176D01*
G01X319547Y156751D02*
X319618Y156822D01*
G01X324232Y164184D02*
X326874D01*
G01X322200Y162152D02*
X324232Y164184D01*
G01X322200Y160890D02*
Y162152D01*
G01X319050Y157740D02*
X322200Y160890D01*
G01X318700Y157740D02*
X319050D01*
G01X318699Y157741D02*
X318700Y157740D01*
G01X318698Y157741D02*
X318699D01*
G01X318627Y157670D02*
X318698Y157741D01*
G01X324967Y185850D02*
X326782D01*
G01X324717Y186100D02*
X324967Y185850D01*
G01X324350Y186100D02*
X324717D01*
G01X324753Y184800D02*
X324350D01*
G01X325003Y185050D02*
X324753Y184800D01*
G01X326450Y185050D02*
X325003D01*
G01X324668Y200075D02*
X327075D01*
G01X324193Y200550D02*
X324668Y200075D01*
G01X323550Y200550D02*
X324193D01*
G01X323300Y200300D02*
X323550Y200550D01*
G01X323200Y200300D02*
X323300D01*
G01X325000Y200875D02*
X326743D01*
G01X324525Y201350D02*
X325000Y200875D01*
G01X323550Y201350D02*
X324525D01*
G01X323300Y201600D02*
X323550Y201350D01*
G01X323200Y201600D02*
X323300D01*
G01X336095Y166463D02*
X336944Y167312D01*
G01X330285Y166463D02*
X336095D01*
G01X327206Y163384D02*
X330285Y166463D01*
G01X326874Y164184D02*
X329953Y167263D01*
G01X338344Y168712D02*
X343192Y173560D01*
G01X338344Y168160D02*
Y168712D01*
G01X337495Y167312D02*
X338344Y168160D01*
G01X336944Y167312D02*
X337495D01*
G01X335763Y167263D02*
X342392Y173892D01*
G01X329953Y167263D02*
X335763D01*
G01X340300Y184900D02*
X341449D01*
G01X339100Y183700D02*
X340300Y184900D01*
G01X328932Y183700D02*
X339100D01*
G01X326782Y185850D02*
X328932Y183700D01*
G01X328600Y182900D02*
X326450Y185050D01*
G01X339432Y182900D02*
X328600D01*
G01X340632Y184100D02*
X339432Y182900D01*
G01X341449Y184100D02*
X340632D01*
G01X326225Y205225D02*
X326125D01*
G01X326475Y205475D02*
X326225Y205225D01*
G01X327675Y205475D02*
X326475D01*
G01X328300Y206100D02*
X327675Y205475D01*
G01X329982Y206100D02*
X328300D01*
G01X330372Y205710D02*
X329982Y206100D01*
G01X331572Y205710D02*
X330372D01*
G01X331962Y206100D02*
X331572Y205710D01*
G01X333162Y206100D02*
X331962D01*
G01X333552Y205710D02*
X333162Y206100D01*
G01X334752Y205710D02*
X333552D01*
G01X335142Y206100D02*
X334752Y205710D01*
G01X337300Y206100D02*
X335142D01*
G01X338300Y205100D02*
X337300Y206100D01*
G01X339500Y205100D02*
X338300D01*
G01X339890Y204710D02*
X339500Y205100D01*
G01X341090Y204710D02*
X339890D01*
G01X326225Y206525D02*
X326125D01*
G01X326475Y206275D02*
X326225Y206525D01*
G01X327343Y206275D02*
X326475D01*
G01X327968Y206900D02*
X327343Y206275D01*
G01X337632Y206900D02*
X327968D01*
G01X338632Y205900D02*
X337632Y206900D01*
G01X353500Y205900D02*
X338632D01*
G01X340368Y202300D02*
X341268Y201400D01*
G01X333932Y202300D02*
X340368D01*
G01X333032Y201400D02*
X333932Y202300D01*
G01X328400Y201400D02*
X333032D01*
G01X327075Y200075D02*
X328400Y201400D01*
G01X340700Y203100D02*
X341600Y202200D01*
G01X333600Y203100D02*
X340700D01*
G01X332700Y202200D02*
X333600Y203100D01*
G01X328068Y202200D02*
X332700D01*
G01X326743Y200875D02*
X328068Y202200D01*
G01X344651Y180816D02*
Y183651D01*
G01X343192Y179357D02*
X344651Y180816D01*
G01X343192Y176957D02*
Y179357D01*
G01X343582Y176567D02*
X343192Y176957D01*
G01X343582Y175367D02*
Y176567D01*
G01X343192Y174977D02*
X343582Y175367D01*
G01X343192Y173560D02*
Y174977D01*
G01X343851Y181148D02*
Y185640D01*
G01X342392Y179689D02*
X343851Y181148D01*
G01X342392Y173892D02*
Y179689D01*
G01X342188Y185639D02*
X342233D01*
G01X341449Y184900D02*
X342188Y185639D01*
G01Y183361D02*
X341449Y184100D01*
G01X344651Y183651D02*
X345500Y184500D01*
G01X343851Y185640D02*
X345631Y187420D01*
G01X341480Y205100D02*
X341090Y204710D01*
G01X342680Y205100D02*
X341480D01*
G01X343070Y204710D02*
X342680Y205100D01*
G01X344270Y204710D02*
X343070D01*
G01X344660Y205100D02*
X344270Y204710D01*
G01X345860Y205100D02*
X344660D01*
G01X346250Y204710D02*
X345860Y205100D01*
G01X347450Y204710D02*
X346250D01*
G01X347840Y205100D02*
X347450Y204710D01*
G01X349040Y205100D02*
X347840D01*
G01X349430Y204710D02*
X349040Y205100D01*
G01X350630Y204710D02*
X349430D01*
G01X351020Y205100D02*
X350630Y204710D01*
G01X353832Y205100D02*
X351020D01*
G01X356200Y207468D02*
X353832Y205100D01*
G01X356200Y210368D02*
Y207468D01*
G01X356832Y211000D02*
X356200Y210368D01*
G01X355400Y207800D02*
X353500Y205900D01*
G01X355400Y210700D02*
Y207800D01*
G01X356500Y211800D02*
X355400Y210700D01*
G01X354032Y201400D02*
X356832Y204200D01*
G01X341268Y201400D02*
X354032D01*
G01X353700Y202200D02*
X356500Y205000D01*
G01X341600Y202200D02*
X353700D01*
G01X342500Y217900D02*
X342400D01*
G01X342750Y218150D02*
X342500Y217900D01*
G01X345950Y218150D02*
X342750D01*
G01X346600Y217500D02*
X345950Y218150D01*
G01X354450Y217500D02*
X346600D01*
G01X356100Y219150D02*
X354450Y217500D01*
G01X359750Y219150D02*
X356100D01*
G01X342500Y219200D02*
X342400D01*
G01X342750Y218950D02*
X342500Y219200D01*
G01X346282Y218950D02*
X342750D01*
G01X346932Y218300D02*
X346282Y218950D01*
G01X354118Y218300D02*
X346932D01*
G01X355768Y219950D02*
X354118Y218300D01*
G01X360082Y219950D02*
X355768D01*
G01X352700Y219450D02*
X352600D01*
G01X352950Y219700D02*
X352700Y219450D01*
G01X354000Y219700D02*
X352950D01*
G01X355300Y221000D02*
X354000Y219700D01*
G01X360600Y221000D02*
X355300D01*
G01X352700Y220750D02*
X352600D01*
G01X352950Y220500D02*
X352700Y220750D01*
G01X353668Y220500D02*
X352950D01*
G01X354968Y221800D02*
X353668Y220500D01*
G01X360932Y221800D02*
X354968D01*
G01X362900Y85386D02*
Y95800D01*
G01X368686Y79600D02*
X362900Y85386D01*
G01X369016Y79600D02*
X368686D01*
G01X369017Y79601D02*
X369016Y79600D01*
G01X373967Y79601D02*
X369017D01*
G01X362100Y89300D02*
X361200Y90200D01*
G01X362100Y85054D02*
Y89300D01*
G01X368354Y78800D02*
X362100Y85054D01*
G01X369348Y78800D02*
X368354D01*
G01X369349Y78801D02*
X369348Y78800D01*
G01X373353Y78801D02*
X369349D01*
G01X362900Y95800D02*
X361200Y97500D01*
G01X363507Y196000D02*
Y200361D01*
G01X362707Y195200D02*
X363507Y196000D01*
G01X362707Y193107D02*
Y195200D01*
G01X364873Y190941D02*
X362707Y193107D01*
G01X364895Y190941D02*
X364873D01*
G01X364307Y195668D02*
Y200693D01*
G01X363507Y194868D02*
X364307Y195668D01*
G01X363507Y193439D02*
Y194868D01*
G01X363898Y193048D02*
X363507Y193439D01*
G01X364854Y193048D02*
X363898D01*
G01X364947Y193141D02*
X364854Y193048D01*
G01X366105Y195390D02*
Y203537D01*
G01X366575Y194920D02*
X366105Y195390D01*
G01X366575Y190800D02*
Y194920D01*
G01X367309Y190066D02*
X366575Y190800D01*
G01X368234Y190066D02*
X367309D01*
G01X369200Y189100D02*
X368234Y190066D01*
G01X366905Y195722D02*
Y203205D01*
G01X367375Y195252D02*
X366905Y195722D01*
G01X367375Y191132D02*
Y195252D01*
G01X367641Y190866D02*
X367375Y191132D01*
G01X368069Y190866D02*
X367641D01*
G01X369106Y191903D02*
X368069Y190866D01*
G01X359807Y192150D02*
X361257Y190700D01*
G01X359807Y195807D02*
Y192150D01*
G01X360672Y196672D02*
X359807Y195807D01*
G01X360672Y198796D02*
Y196672D01*
G01X360607Y194174D02*
X361257Y193524D01*
G01X360607Y195475D02*
Y194174D01*
G01X361472Y196340D02*
X360607Y195475D01*
G01X361472Y199128D02*
Y196340D01*
G01X361500Y202368D02*
Y217400D01*
G01X363507Y200361D02*
X361500Y202368D01*
G01X362300Y210040D02*
Y217732D01*
G01X362690Y209650D02*
X362300Y210040D01*
G01X362690Y208450D02*
Y209650D01*
G01X362300Y208060D02*
X362690Y208450D01*
G01X362300Y206860D02*
Y208060D01*
G01X362690Y206470D02*
X362300Y206860D01*
G01X362690Y205270D02*
Y206470D01*
G01X362300Y204880D02*
X362690Y205270D01*
G01X362300Y202700D02*
Y204880D01*
G01X364307Y200693D02*
X362300Y202700D01*
G01X365500Y212800D02*
X372749Y205551D01*
G01X365500Y219100D02*
Y212800D01*
G01X366300Y213132D02*
X373549Y205883D01*
G01X366300Y219432D02*
Y213132D01*
G01X363600Y212400D02*
Y218000D01*
G01X366700Y209300D02*
X363600Y212400D01*
G01X366700Y204132D02*
Y209300D01*
G01X366105Y203537D02*
X366700Y204132D01*
G01X364400Y212732D02*
Y218332D01*
G01X367500Y209632D02*
X364400Y212732D01*
G01X367500Y203800D02*
Y209632D01*
G01X366905Y203205D02*
X367500Y203800D01*
G01X357718Y211000D02*
X356832D01*
G01X358498Y210220D02*
X357718Y211000D01*
G01X357755Y211800D02*
X356500D01*
G01X358382Y212427D02*
X357755Y211800D01*
G01X359200Y200268D02*
X360672Y198796D01*
G01X359200Y203668D02*
Y200268D01*
G01X358668Y204200D02*
X359200Y203668D01*
G01X356832Y204200D02*
X358668D01*
G01X360000Y200600D02*
X361472Y199128D01*
G01X360000Y204000D02*
Y200600D01*
G01X359000Y205000D02*
X360000Y204000D01*
G01X356500Y205000D02*
X359000D01*
G01X361500Y217400D02*
X359750Y219150D01*
G01X362300Y217732D02*
X360082Y219950D01*
G01X361477Y223123D02*
X365500Y219100D01*
G01X361477Y227200D02*
Y223123D01*
G01X361227Y227450D02*
X361477Y227200D01*
G01X361227Y227500D02*
Y227450D01*
G01X362277Y223455D02*
X366300Y219432D01*
G01X362277Y227200D02*
Y223455D01*
G01X362527Y227450D02*
X362277Y227200D01*
G01X362527Y227500D02*
Y227450D01*
G01X363600Y218000D02*
X360600Y221000D01*
G01X364400Y218332D02*
X360932Y221800D01*
G01X374110Y79600D02*
X373967Y79601D01*
G01X374410Y79300D02*
X374110Y79600D01*
G01X373632Y78522D02*
X373353Y78801D01*
G01X372472Y191878D02*
X374000Y190350D01*
G01X372472Y195130D02*
Y191878D01*
G01X372749Y195407D02*
X372472Y195130D01*
G01X372749Y205551D02*
Y195407D01*
G01X373398Y193626D02*
X373922Y193103D01*
G01X373351Y193672D02*
X373398Y193626D01*
G01X373272Y193753D02*
X373351Y193672D01*
G01X373272Y194798D02*
Y193753D01*
G01X373549Y195075D02*
X373272Y194798D01*
G01X373549Y196275D02*
Y195075D01*
G01X373939Y196665D02*
X373549Y196275D01*
G01X373939Y197865D02*
Y196665D01*
G01X373549Y198255D02*
X373939Y197865D01*
G01X373549Y199455D02*
Y198255D01*
G01X373939Y199845D02*
X373549Y199455D01*
G01X373939Y201045D02*
Y199845D01*
G01X373549Y201435D02*
X373939Y201045D01*
G01X373549Y202635D02*
Y201435D01*
G01X373939Y203025D02*
X373549Y202635D01*
G01X373939Y204225D02*
Y203025D01*
G01X373549Y204615D02*
X373939Y204225D01*
G01X373549Y205883D02*
Y204615D01*
G01X408819Y181419D02*
X410163Y182763D01*
G01X405119Y181419D02*
X408819D01*
G01X403900Y180200D02*
X405119Y181419D01*
G01X403600Y180200D02*
X403900D01*
G01X408487Y182219D02*
X409831Y183563D01*
G01X403781Y182219D02*
X408487D01*
G01X403600Y182400D02*
X403781Y182219D01*
G01X410600Y188900D02*
Y201366D01*
G01X409600Y187900D02*
X410600Y188900D01*
G01X407900Y187900D02*
X409600D01*
G01X407400Y187400D02*
X407900Y187900D01*
G01X407400Y185466D02*
Y187400D01*
G01X408242Y184624D02*
X407400Y185466D01*
G01X405376Y184976D02*
X405231D01*
G01X406600Y186200D02*
X405376Y184976D01*
G01X406600Y187732D02*
Y186200D01*
G01X407568Y188700D02*
X406600Y187732D01*
G01X409268Y188700D02*
X407568D01*
G01X409800Y189232D02*
X409268Y188700D01*
G01X409800Y201698D02*
Y189232D01*
G01X407600Y196100D02*
Y203000D01*
G01X406400Y194900D02*
X407600Y196100D01*
G01X406400Y192300D02*
Y194900D01*
G01X408200Y190500D02*
X406400Y192300D01*
G01X408400Y195768D02*
Y202668D01*
G01X407716Y195084D02*
X408400Y195768D01*
G01X407716Y193984D02*
Y195084D01*
G01X408100Y193600D02*
X407716Y193984D01*
G01X404200Y196110D02*
Y201800D01*
G01X404560Y195750D02*
X404200Y196110D01*
G01X404560Y194330D02*
Y195750D01*
G01X403022Y192792D02*
X404560Y194330D01*
G01X403022Y192094D02*
Y192792D01*
G01X403400Y195438D02*
Y202132D01*
G01X402967Y195005D02*
X403400Y195438D01*
G01X417849Y197800D02*
X419803Y199754D01*
G01X415732Y197800D02*
X417849D01*
G01X415050Y197118D02*
X415732Y197800D01*
G01X415050Y193950D02*
Y197118D01*
G01X414500Y193400D02*
X415050Y193950D01*
G01X414500Y183900D02*
Y193400D01*
G01X413363Y182763D02*
X414500Y183900D01*
G01X410163Y182763D02*
X413363D01*
G01X414250Y197450D02*
X415400Y198600D01*
G01X414250Y194282D02*
Y197450D01*
G01X413700Y193732D02*
X414250Y194282D01*
G01X413700Y184232D02*
Y193732D01*
G01X413031Y183563D02*
X413700Y184232D01*
G01X409831Y183563D02*
X413031D01*
G01X415487Y203000D02*
X418987Y206500D01*
G01X412234Y203000D02*
X415487D01*
G01X410600Y201366D02*
X412234Y203000D01*
G01X411902Y203800D02*
X409800Y201698D01*
G01X415155Y203800D02*
X411902D01*
G01X418655Y207300D02*
X415155Y203800D01*
G01X414099Y209499D02*
X421267D01*
G01X407600Y203000D02*
X414099Y209499D01*
G01X414431Y208699D02*
X421599D01*
G01X408400Y202668D02*
X414431Y208699D01*
G01X413274Y210874D02*
X418211D01*
G01X404200Y201800D02*
X413274Y210874D01*
G01X417879Y211674D02*
X421300Y215095D01*
G01X412942Y211674D02*
X417879D01*
G01X403400Y202132D02*
X412942Y211674D01*
G01X417517Y198600D02*
X419003Y200086D01*
G01X415400Y198600D02*
X417517D01*
G01X421563Y161900D02*
X420804Y162659D01*
G01X424795Y161900D02*
X421563D01*
G01X425898Y163003D02*
X424795Y161900D01*
G01X432829Y163003D02*
X425898D01*
G01X433532Y162300D02*
X432829Y163003D01*
G01X421963Y161100D02*
X420900Y160037D01*
G01X425127Y161100D02*
X421963D01*
G01X426230Y162203D02*
X425127Y161100D01*
G01X432497Y162203D02*
X426230D01*
G01X433200Y161500D02*
X432497Y162203D01*
G01X436127Y161500D02*
X433200D01*
G01X425795Y206500D02*
X426271Y206024D01*
G01X418987Y206500D02*
X425795D01*
G01X425897Y207300D02*
X418655D01*
G01X426271Y207674D02*
X425897Y207300D01*
G01X423500Y211732D02*
Y212200D01*
G01X421267Y209499D02*
X423500Y211732D01*
G01X423933Y211033D02*
X424667D01*
G01X421599Y208699D02*
X423933Y211033D01*
G01X418211Y210874D02*
X421022Y213685D01*
G01X427600Y200000D02*
X428450Y199150D01*
G01X427300Y200000D02*
X427600D01*
G01X422800Y204500D02*
X427300Y200000D01*
G01X420600Y204500D02*
X422800D01*
G01X419803Y203703D02*
X420600Y204500D01*
G01X419803Y199754D02*
Y203703D01*
G01X427632Y200800D02*
X428450D01*
G01X423132Y205300D02*
X427632Y200800D01*
G01X420268Y205300D02*
X423132D01*
G01X419003Y204035D02*
X420268Y205300D01*
G01X419003Y200086D02*
Y204035D01*
G01X421704Y213685D02*
X421717Y213698D01*
G01X421022Y213685D02*
X421704D01*
G01X421300Y215095D02*
Y215615D01*
G01X435795Y162300D02*
X433532D01*
G01X438698Y165203D02*
X435795Y162300D01*
G01X441246Y165203D02*
X438698D01*
G01X441480Y165437D02*
X441246Y165203D01*
G01X439030Y164403D02*
X436127Y161500D01*
G01X441246Y164403D02*
X439030D01*
G01X441312Y164337D02*
X441246Y164403D01*
G01X441653Y164337D02*
X441312D01*
G54D11*
G01X-31497Y-1D02*
X26377D01*
G01X-35434Y3936D02*
G03X-31497Y-1I3937J0D01*
G01X-35434Y585039D02*
Y3936D01*
G01X-7874Y588976D02*
X-31497D01*
G01D02*
G03X-35434Y585039I0J-3937D01*
G01X-12698Y15747D02*
G03I-6988J0D01*
G01Y573227D02*
G03I-6988J0D01*
G01X822835Y290551D02*
X3937D01*
G03X0Y286614I0J-3937D01*
G01Y61811D01*
G03X3937Y57874I3937J0D01*
G01X53937D01*
G02X57874Y53937I0J-3937D01*
G01Y16142D01*
X338189D01*
Y39961D01*
G02X345669I3740J0D01*
G01Y16142D01*
X389764D01*
Y42126D01*
G02X393701Y46063I3937J0D01*
G01X409449D01*
G02X413386Y42126I0J-3937D01*
G01Y3937D01*
G03X417323Y0I3937J0D01*
G01X822835D01*
G03X826772Y3937I0J3937D01*
G01Y286614D01*
G03X822835Y290551I-3937J0D01*
G01X826773Y286614D02*
G03X822836Y290551I-3937J0D01*
G01X3938D01*
G03X1Y286614I0J-3937D01*
G01Y61811D01*
G03X3938Y57874I3937J0D01*
G01X53938D01*
G02X57875Y53937I0J-3937D01*
G01Y12598D01*
X59844Y10629D01*
X336222D01*
X338190Y12598D01*
Y39960D01*
G02X345671I3740J0D01*
G01Y12598D01*
X347639Y10629D01*
X387797D01*
X389765Y12598D01*
Y42126D01*
G02X393702Y46063I3937J0D01*
G01X409450D01*
G02X413387Y42126I0J-3937D01*
G01Y3937D01*
G03X417324Y0I3937J0D01*
G01X822836D01*
G03X826773Y3937I0J3937D01*
G01Y286614D01*
G01D02*
G03X822836Y290551I-3937J0D01*
G01X3938D01*
G03X1Y286614I0J-3937D01*
G01Y61811D01*
G03X3938Y57874I3937J0D01*
G01X53938D01*
G02X57875Y53937I0J-3937D01*
G01Y12598D01*
X59844Y10629D01*
X336222D01*
X338190Y12598D01*
Y39960D01*
G02X345671I3740J0D01*
G01Y12598D01*
X347639Y10629D01*
X387797D01*
X389765Y12598D01*
Y42126D01*
G02X393702Y46063I3937J0D01*
G01X409450D01*
G02X413387Y42126I0J-3937D01*
G01Y3937D01*
G03X417324Y0I3937J0D01*
G01X822836D01*
G03X826773Y3937I0J3937D01*
G01Y286614D01*
G01X22440Y49999D02*
X-3937D01*
G01X-7874Y53936D02*
Y72440D01*
G01Y53936D02*
G03X-3937Y49999I3937J0D01*
G01X0Y72440D02*
G03X-7874I-3937J0D01*
G01Y103149D02*
G03X0I3937J0D01*
G01X-7874D02*
Y210235D01*
G01X0D02*
G03X-7874I-3937J0D01*
G01Y240944D02*
Y348031D01*
G01Y240944D02*
G03X0I3937J0D01*
G01X-3Y302361D02*
G03X3934Y298424I3937J0D01*
G01X822832D01*
G03X826769Y302361I0J3937D01*
G01Y527164D01*
G03X822832Y531101I-3937J0D01*
G01X772832D01*
G02X768895Y535038I0J3937D01*
G01Y576377D01*
X766926Y578346D01*
X490548D01*
X488580Y576377D01*
Y549015D01*
G02X481099I-3740J0D01*
G01Y576377D01*
X479131Y578346D01*
X438973D01*
X437005Y576377D01*
Y546849D01*
G02X433068Y542912I-3937J0D01*
G01X417320D01*
G02X413383Y546849I0J3937D01*
G01Y585038D01*
G03X409446Y588975I-3937J0D01*
G01X3934D01*
G03X-3Y585038I0J-3937D01*
G01Y302361D01*
G01X0Y348031D02*
G03X-7874I-3937J0D01*
G01Y378739D02*
Y485826D01*
G01Y378739D02*
G03X0I3937J0D01*
G01Y485826D02*
G03X-7874I-3937J0D01*
G01Y516535D02*
Y588976D01*
G01Y516535D02*
G03X0I3937J-1D01*
G01X17137Y687650D02*
Y675650D01*
G01X14837Y687650D02*
X19437D01*
G01X21437Y675650D02*
Y687650D01*
G01Y681850D02*
X21937Y682850D01*
X22437Y683450D01*
X23237Y683650D01*
X23837Y683450D01*
X24537Y682650D01*
X24837Y681450D01*
Y675650D01*
G01X29137Y683650D02*
Y675650D01*
G01Y686850D02*
X28937Y687050D01*
Y687450D01*
X29137Y687650D01*
X29337Y687450D01*
Y687050D01*
X29137Y686850D01*
G01X33637Y677050D02*
X34137Y676250D01*
X34837Y675650D01*
X35437D01*
X36037Y676050D01*
X36437Y676650D01*
X36637Y677450D01*
X36537Y678650D01*
X36137Y679250D01*
X34337Y680450D01*
X33937Y681850D01*
X34137Y682850D01*
X34537Y683450D01*
X35137Y683650D01*
X35737Y683450D01*
X36337Y682850D01*
G01X45737Y672650D02*
X46437Y671850D01*
X47237Y671650D01*
X47937Y671850D01*
X48537Y672850D01*
X48937Y674250D01*
Y683650D01*
G01Y682050D02*
X48537Y682850D01*
X47937Y683450D01*
X47237Y683650D01*
X46437Y683250D01*
X45937Y682450D01*
X45537Y681050D01*
X45337Y679650D01*
X45437Y678450D01*
X45837Y677050D01*
X46437Y676050D01*
X47237Y675650D01*
X47837Y675850D01*
X48537Y676650D01*
X48937Y677450D01*
G01X51637Y681050D02*
X54837D01*
X54537Y682450D01*
X54037Y683250D01*
X53337Y683650D01*
X52637Y683450D01*
X52037Y682850D01*
X51637Y681450D01*
X51437Y680250D01*
Y679050D01*
X51637Y677850D01*
X52137Y676650D01*
X52737Y675850D01*
X53437Y675650D01*
X54137Y676050D01*
X54837Y677250D01*
G01X57737Y675650D02*
Y683650D01*
G01Y682050D02*
X58237Y682850D01*
X58737Y683450D01*
X59437Y683650D01*
X59937Y683450D01*
X60537Y682850D01*
G01X63337Y675650D02*
Y687650D01*
G01Y681650D02*
X63837Y682850D01*
X64437Y683450D01*
X65037Y683650D01*
X65937Y683250D01*
X66537Y682450D01*
X66937Y681050D01*
Y679450D01*
X66737Y677850D01*
X66337Y676650D01*
X65637Y675850D01*
X65037Y675650D01*
X64437Y675850D01*
X63837Y676450D01*
X63337Y677450D01*
G01X69637Y681050D02*
X72837D01*
X72537Y682450D01*
X72037Y683250D01*
X71337Y683650D01*
X70637Y683450D01*
X70037Y682850D01*
X69637Y681450D01*
X69437Y680250D01*
Y679050D01*
X69637Y677850D01*
X70137Y676650D01*
X70737Y675850D01*
X71437Y675650D01*
X72137Y676050D01*
X72837Y677250D01*
G01X75737Y675650D02*
Y683650D01*
G01Y682050D02*
X76237Y682850D01*
X76737Y683450D01*
X77437Y683650D01*
X77937Y683450D01*
X78537Y682850D01*
G01X89137Y683650D02*
Y675650D01*
G01Y686850D02*
X88937Y687050D01*
Y687450D01*
X89137Y687650D01*
X89337Y687450D01*
Y687050D01*
X89137Y686850D01*
G01X93637Y677050D02*
X94137Y676250D01*
X94837Y675650D01*
X95437D01*
X96037Y676050D01*
X96437Y676650D01*
X96637Y677450D01*
X96537Y678650D01*
X96137Y679250D01*
X94337Y680450D01*
X93937Y681850D01*
X94137Y682850D01*
X94537Y683450D01*
X95137Y683650D01*
X95737Y683450D01*
X96337Y682850D01*
G01X105537Y672650D02*
X106237Y671850D01*
X106837Y671650D01*
X107637Y672050D01*
X108237Y673050D01*
X108537Y674850D01*
Y683650D01*
G01Y686850D02*
X108337Y687050D01*
Y687450D01*
X108537Y687650D01*
X108737Y687450D01*
Y687050D01*
X108537Y686850D01*
G01X111437Y683650D02*
Y678050D01*
X111837Y676650D01*
X112437Y675850D01*
X113137Y675650D01*
X113837Y675850D01*
X114437Y676650D01*
X114837Y678050D01*
G01Y675650D02*
Y683650D01*
G01X117637Y677050D02*
X118137Y676250D01*
X118837Y675650D01*
X119437D01*
X120037Y676050D01*
X120437Y676650D01*
X120637Y677450D01*
X120537Y678650D01*
X120137Y679250D01*
X118337Y680450D01*
X117937Y681850D01*
X118137Y682850D01*
X118537Y683450D01*
X119137Y683650D01*
X119737Y683450D01*
X120337Y682850D01*
G01X125137Y687650D02*
Y675650D01*
G01X123737Y683650D02*
X126537D01*
G01X136537Y675650D02*
Y685850D01*
X136737Y686850D01*
X137137Y687450D01*
X137737Y687650D01*
X138337Y687250D01*
X138637Y686250D01*
G01X137437Y682850D02*
X135437D01*
G01X143137Y675650D02*
X142537Y675850D01*
X141937Y676650D01*
X141537Y678050D01*
X141337Y679650D01*
X141537Y681250D01*
X141937Y682650D01*
X142537Y683450D01*
X143137Y683650D01*
X143737Y683450D01*
X144337Y682650D01*
X144737Y681250D01*
X144837Y679650D01*
X144737Y678050D01*
X144337Y676650D01*
X143737Y675850D01*
X143137Y675650D01*
G01X147737D02*
Y683650D01*
G01Y682050D02*
X148237Y682850D01*
X148737Y683450D01*
X149437Y683650D01*
X149937Y683450D01*
X150537Y682850D01*
G01X159037Y672050D02*
X159637Y671650D01*
X160437Y672050D01*
X160937Y672850D01*
X161337Y673850D01*
X161937Y677050D01*
X163237Y683650D01*
G01X160037D02*
X161937Y677050D01*
G01X167137Y675650D02*
X166537Y675850D01*
X165937Y676650D01*
X165537Y678050D01*
X165337Y679650D01*
X165537Y681250D01*
X165937Y682650D01*
X166537Y683450D01*
X167137Y683650D01*
X167737Y683450D01*
X168337Y682650D01*
X168737Y681250D01*
X168837Y679650D01*
X168737Y678050D01*
X168337Y676650D01*
X167737Y675850D01*
X167137Y675650D01*
G01X171437Y683650D02*
Y678050D01*
X171837Y676650D01*
X172437Y675850D01*
X173137Y675650D01*
X173837Y675850D01*
X174437Y676650D01*
X174837Y678050D01*
G01Y675650D02*
Y683650D01*
G01X183737Y675650D02*
Y683650D01*
G01Y682050D02*
X184237Y682850D01*
X184737Y683450D01*
X185437Y683650D01*
X185937Y683450D01*
X186537Y682850D01*
G01X189637Y681050D02*
X192837D01*
X192537Y682450D01*
X192037Y683250D01*
X191337Y683650D01*
X190637Y683450D01*
X190037Y682850D01*
X189637Y681450D01*
X189437Y680250D01*
Y679050D01*
X189637Y677850D01*
X190137Y676650D01*
X190737Y675850D01*
X191437Y675650D01*
X192137Y676050D01*
X192837Y677250D01*
G01X196537Y675650D02*
Y685850D01*
X196737Y686850D01*
X197137Y687450D01*
X197737Y687650D01*
X198337Y687250D01*
X198637Y686250D01*
G01X197437Y682850D02*
X195437D01*
G01X201637Y681050D02*
X204837D01*
X204537Y682450D01*
X204037Y683250D01*
X203337Y683650D01*
X202637Y683450D01*
X202037Y682850D01*
X201637Y681450D01*
X201437Y680250D01*
Y679050D01*
X201637Y677850D01*
X202137Y676650D01*
X202737Y675850D01*
X203437Y675650D01*
X204137Y676050D01*
X204837Y677250D01*
G01X207737Y675650D02*
Y683650D01*
G01Y682050D02*
X208237Y682850D01*
X208737Y683450D01*
X209437Y683650D01*
X209937Y683450D01*
X210537Y682850D01*
G01X213637Y681050D02*
X216837D01*
X216537Y682450D01*
X216037Y683250D01*
X215337Y683650D01*
X214637Y683450D01*
X214037Y682850D01*
X213637Y681450D01*
X213437Y680250D01*
Y679050D01*
X213637Y677850D01*
X214137Y676650D01*
X214737Y675850D01*
X215437Y675650D01*
X216137Y676050D01*
X216837Y677250D01*
G01X219437Y675650D02*
Y683650D01*
G01Y681650D02*
X219837Y682650D01*
X220437Y683450D01*
X221237Y683650D01*
X221937Y683450D01*
X222537Y682650D01*
X222837Y681250D01*
Y675650D01*
G01X228737Y682650D02*
X228037Y683450D01*
X227437Y683650D01*
X226637Y683250D01*
X226037Y682450D01*
X225637Y681050D01*
X225537Y679650D01*
X225637Y678250D01*
X226037Y677050D01*
X226637Y676050D01*
X227437Y675650D01*
X228137Y676050D01*
X228737Y676850D01*
G01X231637Y681050D02*
X234837D01*
X234537Y682450D01*
X234037Y683250D01*
X233337Y683650D01*
X232637Y683450D01*
X232037Y682850D01*
X231637Y681450D01*
X231437Y680250D01*
Y679050D01*
X231637Y677850D01*
X232137Y676650D01*
X232737Y675850D01*
X233437Y675650D01*
X234137Y676050D01*
X234837Y677250D01*
G01X245137Y687650D02*
Y675650D01*
G01X243737Y683650D02*
X246537D01*
G01X251137Y675650D02*
X250537Y675850D01*
X249937Y676650D01*
X249537Y678050D01*
X249337Y679650D01*
X249537Y681250D01*
X249937Y682650D01*
X250537Y683450D01*
X251137Y683650D01*
X251737Y683450D01*
X252337Y682650D01*
X252737Y681250D01*
X252837Y679650D01*
X252737Y678050D01*
X252337Y676650D01*
X251737Y675850D01*
X251137Y675650D01*
G01X262537D02*
Y685850D01*
X262737Y686850D01*
X263137Y687450D01*
X263737Y687650D01*
X264337Y687250D01*
X264637Y686250D01*
G01X263437Y682850D02*
X261437D01*
G01X269137Y683650D02*
Y675650D01*
G01Y686850D02*
X268937Y687050D01*
Y687450D01*
X269137Y687650D01*
X269337Y687450D01*
Y687050D01*
X269137Y686850D01*
G01X273437Y675650D02*
Y683650D01*
G01Y681650D02*
X273837Y682650D01*
X274437Y683450D01*
X275237Y683650D01*
X275937Y683450D01*
X276537Y682650D01*
X276837Y681250D01*
Y675650D01*
G01X282937Y687650D02*
Y675650D01*
G01Y677450D02*
X282537Y676450D01*
X281937Y675850D01*
X281237Y675650D01*
X280437Y676050D01*
X279837Y677050D01*
X279437Y678250D01*
X279337Y679650D01*
X279437Y681050D01*
X279837Y682250D01*
X280437Y683250D01*
X281237Y683650D01*
X281937Y683450D01*
X282437Y683050D01*
X282937Y682250D01*
G01X293137Y687650D02*
Y675650D01*
G01X291737Y683650D02*
X294537D01*
G01X297437Y675650D02*
Y687650D01*
G01Y681850D02*
X297937Y682850D01*
X298437Y683450D01*
X299237Y683650D01*
X299837Y683450D01*
X300537Y682650D01*
X300837Y681450D01*
Y675650D01*
G01X303637Y681050D02*
X306837D01*
X306537Y682450D01*
X306037Y683250D01*
X305337Y683650D01*
X304637Y683450D01*
X304037Y682850D01*
X303637Y681450D01*
X303437Y680250D01*
Y679050D01*
X303637Y677850D01*
X304137Y676650D01*
X304737Y675850D01*
X305437Y675650D01*
X306137Y676050D01*
X306837Y677250D01*
G01X318937Y687650D02*
Y675650D01*
G01Y677450D02*
X318537Y676450D01*
X317937Y675850D01*
X317237Y675650D01*
X316437Y676050D01*
X315837Y677050D01*
X315437Y678250D01*
X315337Y679650D01*
X315437Y681050D01*
X315837Y682250D01*
X316437Y683250D01*
X317237Y683650D01*
X317937Y683450D01*
X318437Y683050D01*
X318937Y682250D01*
G01X323137Y683650D02*
Y675650D01*
G01Y686850D02*
X322937Y687050D01*
Y687450D01*
X323137Y687650D01*
X323337Y687450D01*
Y687050D01*
X323137Y686850D01*
G01X328537Y675650D02*
Y685850D01*
X328737Y686850D01*
X329137Y687450D01*
X329737Y687650D01*
X330337Y687250D01*
X330637Y686250D01*
G01X329437Y682850D02*
X327437D01*
G01X334537Y675650D02*
Y685850D01*
X334737Y686850D01*
X335137Y687450D01*
X335737Y687650D01*
X336337Y687250D01*
X336637Y686250D01*
G01X335437Y682850D02*
X333437D01*
G01X339637Y681050D02*
X342837D01*
X342537Y682450D01*
X342037Y683250D01*
X341337Y683650D01*
X340637Y683450D01*
X340037Y682850D01*
X339637Y681450D01*
X339437Y680250D01*
Y679050D01*
X339637Y677850D01*
X340137Y676650D01*
X340737Y675850D01*
X341437Y675650D01*
X342137Y676050D01*
X342837Y677250D01*
G01X345737Y675650D02*
Y683650D01*
G01Y682050D02*
X346237Y682850D01*
X346737Y683450D01*
X347437Y683650D01*
X347937Y683450D01*
X348537Y682850D01*
G01X351637Y681050D02*
X354837D01*
X354537Y682450D01*
X354037Y683250D01*
X353337Y683650D01*
X352637Y683450D01*
X352037Y682850D01*
X351637Y681450D01*
X351437Y680250D01*
Y679050D01*
X351637Y677850D01*
X352137Y676650D01*
X352737Y675850D01*
X353437Y675650D01*
X354137Y676050D01*
X354837Y677250D01*
G01X357437Y675650D02*
Y683650D01*
G01Y681650D02*
X357837Y682650D01*
X358437Y683450D01*
X359237Y683650D01*
X359937Y683450D01*
X360537Y682650D01*
X360837Y681250D01*
Y675650D01*
G01X365137Y687650D02*
Y675650D01*
G01X363737Y683650D02*
X366537D01*
G01X371137D02*
Y675650D01*
G01Y686850D02*
X370937Y687050D01*
Y687450D01*
X371137Y687650D01*
X371337Y687450D01*
Y687050D01*
X371137Y686850D01*
G01X378937Y675650D02*
Y683650D01*
G01Y682250D02*
X378537Y683050D01*
X377937Y683450D01*
X377237Y683650D01*
X376537Y683250D01*
X375937Y682450D01*
X375537Y681250D01*
X375337Y679650D01*
X375537Y678050D01*
X375937Y676850D01*
X376537Y676050D01*
X377237Y675650D01*
X377937Y675850D01*
X378537Y676450D01*
X378937Y677250D01*
G01X383137Y675650D02*
Y687650D01*
G01X395137D02*
Y675650D01*
G01X393737Y683650D02*
X396537D01*
G01X399737Y675650D02*
Y683650D01*
G01Y682050D02*
X400237Y682850D01*
X400737Y683450D01*
X401437Y683650D01*
X401937Y683450D01*
X402537Y682850D01*
G01X408937Y675650D02*
Y683650D01*
G01Y682250D02*
X408537Y683050D01*
X407937Y683450D01*
X407237Y683650D01*
X406537Y683250D01*
X405937Y682450D01*
X405537Y681250D01*
X405337Y679650D01*
X405537Y678050D01*
X405937Y676850D01*
X406537Y676050D01*
X407237Y675650D01*
X407937Y675850D01*
X408537Y676450D01*
X408937Y677250D01*
G01X414737Y682650D02*
X414037Y683450D01*
X413437Y683650D01*
X412637Y683250D01*
X412037Y682450D01*
X411637Y681050D01*
X411537Y679650D01*
X411637Y678250D01*
X412037Y677050D01*
X412637Y676050D01*
X413437Y675650D01*
X414137Y676050D01*
X414737Y676850D01*
G01X417637Y681050D02*
X420837D01*
X420537Y682450D01*
X420037Y683250D01*
X419337Y683650D01*
X418637Y683450D01*
X418037Y682850D01*
X417637Y681450D01*
X417437Y680250D01*
Y679050D01*
X417637Y677850D01*
X418137Y676650D01*
X418737Y675850D01*
X419437Y675650D01*
X420137Y676050D01*
X420837Y677250D01*
G01X423637Y677050D02*
X424137Y676250D01*
X424837Y675650D01*
X425437D01*
X426037Y676050D01*
X426437Y676650D01*
X426637Y677450D01*
X426537Y678650D01*
X426137Y679250D01*
X424337Y680450D01*
X423937Y681850D01*
X424137Y682850D01*
X424537Y683450D01*
X425137Y683650D01*
X425737Y683450D01*
X426337Y682850D01*
G01X437137Y683650D02*
Y675650D01*
G01Y686850D02*
X436937Y687050D01*
Y687450D01*
X437137Y687650D01*
X437337Y687450D01*
Y687050D01*
X437137Y686850D01*
G01X441437Y675650D02*
Y683650D01*
G01Y681650D02*
X441837Y682650D01*
X442437Y683450D01*
X443237Y683650D01*
X443937Y683450D01*
X444537Y682650D01*
X444837Y681250D01*
Y675650D01*
G01X455137D02*
Y687650D01*
G01X462937Y675650D02*
Y683650D01*
G01Y682250D02*
X462537Y683050D01*
X461937Y683450D01*
X461237Y683650D01*
X460537Y683250D01*
X459937Y682450D01*
X459537Y681250D01*
X459337Y679650D01*
X459537Y678050D01*
X459937Y676850D01*
X460537Y676050D01*
X461237Y675650D01*
X461937Y675850D01*
X462537Y676450D01*
X462937Y677250D01*
G01X465037Y672050D02*
X465637Y671650D01*
X466437Y672050D01*
X466937Y672850D01*
X467337Y673850D01*
X467937Y677050D01*
X469237Y683650D01*
G01X466037D02*
X467937Y677050D01*
G01X471637Y681050D02*
X474837D01*
X474537Y682450D01*
X474037Y683250D01*
X473337Y683650D01*
X472637Y683450D01*
X472037Y682850D01*
X471637Y681450D01*
X471437Y680250D01*
Y679050D01*
X471637Y677850D01*
X472137Y676650D01*
X472737Y675850D01*
X473437Y675650D01*
X474137Y676050D01*
X474837Y677250D01*
G01X477737Y675650D02*
Y683650D01*
G01Y682050D02*
X478237Y682850D01*
X478737Y683450D01*
X479437Y683650D01*
X479937Y683450D01*
X480537Y682850D01*
G01X489137Y687650D02*
Y675650D01*
X493137D01*
G01X497137D02*
X497837Y675850D01*
X498637Y676450D01*
X499137Y677450D01*
X499337Y678850D01*
X499137Y680250D01*
X498537Y681450D01*
X497637Y682050D01*
X496637D01*
X496037Y682450D01*
X495537Y683450D01*
X495337Y684850D01*
X495637Y686250D01*
X496337Y687250D01*
X497137Y687650D01*
X497937Y687250D01*
X498637Y686250D01*
X498937Y684850D01*
X498737Y683450D01*
X498237Y682450D01*
X497637Y682050D01*
X496637D01*
X495737Y681450D01*
X495137Y680250D01*
X494937Y678850D01*
X495137Y677450D01*
X495637Y676450D01*
X496437Y675850D01*
X497137Y675650D01*
G01X26377Y-1D02*
Y46062D01*
G01D02*
G03X22440Y49999I-3937J0D01*
G01X102756Y290550D02*
G03Y298424I0J3937D01*
G01X133465D02*
G03Y290550I0J-3937D01*
G01X299606Y290551D02*
G03Y298425I0J3937D01*
G01X330314D02*
G03Y290551I0J-3937D01*
G01X353350Y224807D02*
X347051D01*
G02Y237406I0J6299D01*
G01X353350D01*
G02Y224807I0J-6299D01*
G01X496457Y290550D02*
G03Y298424I0J3937D01*
G01X527166D02*
G03Y290550I0J-3937D01*
G01X693308D02*
G03Y298424I0J3937D01*
G01X724016D02*
G03Y290550I0J-3937D01*
G01X800393Y588976D02*
Y542913D01*
G01D02*
G03X804330Y538976I3937J0D01*
G01X858267Y588976D02*
X800393D01*
G01X804330Y538976D02*
X830708D01*
G01X834645Y72440D02*
G03X826771I-3937J0D01*
G01Y103149D02*
G03X834645I3937J0D01*
G01Y210235D02*
G03X826771I-3937J0D01*
G01Y240944D02*
G03X834645I3937J0D01*
G01Y348031D02*
G03X826771I-3937J0D01*
G01Y378739D02*
G03X834645I3937J0D01*
G01Y485826D02*
G03X826771I-3937J0D01*
G01Y516535D02*
G03X834645I3937J-1D01*
G01Y535039D02*
G03X830708Y538976I-3937J0D01*
G01X834645Y72440D02*
Y-1D01*
G01D02*
X858267D01*
G01X853444Y15747D02*
G03I-6988J0D01*
G01X834645Y210235D02*
Y103149D01*
G01Y348031D02*
Y240944D01*
G01Y485826D02*
Y378739D01*
G01Y535039D02*
Y516535D01*
G01X853444Y573227D02*
G03I-6988J0D01*
G01X862204Y3936D02*
Y585039D01*
G01X858267Y-1D02*
G03X862204Y3936I0J3937D01*
G01Y585039D02*
G03X858267Y588976I-3937J0D01*
G01X386046Y67664D02*
X374410Y79300D01*
G01X420204Y67664D02*
X386046D01*
G01X385590Y66564D02*
X419748D01*
G01X373632Y78522D02*
X385590Y66564D01*
G01X374600Y212700D02*
Y230700D01*
G01X376300Y211000D02*
X374600Y212700D01*
G01X375700Y216800D02*
Y230244D01*
G01X376300Y216200D02*
X375700Y216800D01*
G01X379588Y243856D02*
X396732Y261000D01*
G01X379588Y235688D02*
Y243856D01*
G01X374600Y230700D02*
X379588Y235688D01*
G01X380688Y243400D02*
X397188Y259900D01*
G01X380688Y235232D02*
Y243400D01*
G01X375700Y230244D02*
X380688Y235232D01*
G01X396732Y261000D02*
X406616D01*
G01X397188Y259900D02*
X458344D01*
G01X418066Y261490D02*
X418556Y261000D01*
G01X416266Y261490D02*
X418066D01*
G01X415776Y261000D02*
X416266Y261490D01*
G01X413976Y261000D02*
X415776D01*
G01X413486Y261490D02*
X413976Y261000D01*
G01X411686Y261490D02*
X413486D01*
G01X411196Y261000D02*
X411686Y261490D01*
G01X409396Y261000D02*
X411196D01*
G01X408906Y261490D02*
X409396Y261000D01*
G01X407106Y261490D02*
X408906D01*
G01X406616Y261000D02*
X407106Y261490D01*
G01X448068Y39800D02*
X420204Y67664D01*
G01X419748Y66564D02*
X447612Y38700D01*
G01X432795Y261000D02*
X434595D01*
G01X432305Y261490D02*
X432795Y261000D01*
G01X430505Y261490D02*
X432305D01*
G01X430015Y261000D02*
X430505Y261490D01*
G01X425288Y261000D02*
X430015D01*
G01X424798Y261490D02*
X425288Y261000D01*
G01X422998Y261490D02*
X424798D01*
G01X422508Y261000D02*
X422998Y261490D01*
G01X418556Y261000D02*
X422508D01*
G01X450000Y39800D02*
X448068D01*
G01X447612Y38700D02*
X449544D01*
G01X445719Y165437D02*
X441480D01*
G01X447456Y163700D02*
X445719Y165437D01*
G01X465044Y163700D02*
X447456D01*
G01X445263Y164337D02*
X441653D01*
G01X447000Y162600D02*
X445263Y164337D01*
G01X465500Y162600D02*
X447000D01*
G01X448825Y261490D02*
X450625D01*
G01X448335Y261000D02*
X448825Y261490D01*
G01X446535Y261000D02*
X448335D01*
G01X446045Y261490D02*
X446535Y261000D01*
G01X444245Y261490D02*
X446045D01*
G01X443755Y261000D02*
X444245Y261490D01*
G01X441955Y261000D02*
X443755D01*
G01X441465Y261490D02*
X441955Y261000D01*
G01X439665Y261490D02*
X441465D01*
G01X439175Y261000D02*
X439665Y261490D01*
G01X437375Y261000D02*
X439175D01*
G01X436885Y261490D02*
X437375Y261000D01*
G01X435085Y261490D02*
X436885D01*
G01X434595Y261000D02*
X435085Y261490D01*
G01X454300Y35500D02*
X450000Y39800D01*
G01X474856Y35500D02*
X454300D01*
G01X464355Y34400D02*
X464845Y33910D01*
G01X462555Y34400D02*
X464355D01*
G01X462065Y33910D02*
X462555Y34400D01*
G01X460265Y33910D02*
X462065D01*
G01X459775Y34400D02*
X460265Y33910D01*
G01X453844Y34400D02*
X459775D01*
G01X452644Y35600D02*
X453844Y34400D01*
G01X451700Y35600D02*
X452644D01*
G01X450722Y36578D02*
X451700Y35600D01*
G01X450722Y37522D02*
Y36578D01*
G01X449544Y38700D02*
X450722Y37522D01*
G01X460887Y258913D02*
X489587D01*
G01X458800Y261000D02*
X460887Y258913D01*
G01X460431Y257813D02*
X489131D01*
G01X458344Y259900D02*
X460431Y257813D01*
G01X455695Y261000D02*
X458800D01*
G01X455205Y261490D02*
X455695Y261000D01*
G01X453405Y261490D02*
X455205D01*
G01X452915Y261000D02*
X453405Y261490D01*
G01X451115Y261000D02*
X452915D01*
G01X450625Y261490D02*
X451115Y261000D01*
G01X476100Y34256D02*
X474856Y35500D01*
G01X476100Y31300D02*
Y34256D01*
G01X476700Y30700D02*
X476100Y31300D01*
G01X477900Y30700D02*
X476700D01*
G01X478500Y31300D02*
X477900Y30700D01*
G01X478500Y34256D02*
Y31300D01*
G01X479744Y35500D02*
X478500Y34256D01*
G01X479600Y33800D02*
X480200Y34400D01*
G01X479600Y30844D02*
Y33800D01*
G01X478356Y29600D02*
X479600Y30844D01*
G01X476244Y29600D02*
X478356D01*
G01X475000Y30844D02*
X476244Y29600D01*
G01X475000Y33800D02*
Y30844D01*
G01X474400Y34400D02*
X475000Y33800D01*
G01X471715Y34400D02*
X474400D01*
G01X471225Y33910D02*
X471715Y34400D01*
G01X469425Y33910D02*
X471225D01*
G01X468935Y34400D02*
X469425Y33910D01*
G01X467135Y34400D02*
X468935D01*
G01X466645Y33910D02*
X467135Y34400D01*
G01X464845Y33910D02*
X466645D01*
G01X467831Y166487D02*
X465044Y163700D01*
G01X601608Y166487D02*
X467831D01*
G01X468287Y165387D02*
X465500Y162600D01*
G01X602064Y165387D02*
X468287D01*
G01X487415Y35500D02*
X479744D01*
G01X488015Y36100D02*
X487415Y35500D01*
G01X488015Y38356D02*
Y36100D01*
G01X489259Y39600D02*
X488015Y38356D01*
G01X491471Y39600D02*
X489259D01*
G01X492715Y38356D02*
X491471Y39600D01*
G01X492715Y35300D02*
Y38356D01*
G01X493315Y34700D02*
X492715Y35300D01*
G01X494600Y34700D02*
X493315D01*
G01X495200Y35300D02*
X494600Y34700D01*
G01X496344Y39400D02*
X495200Y38256D01*
G01X495056Y33600D02*
X496300Y34844D01*
G01X492859Y33600D02*
X495056D01*
G01X491615Y34844D02*
X492859Y33600D01*
G01X491615Y37900D02*
Y34844D01*
G01X491015Y38500D02*
X491615Y37900D01*
G01X489715Y38500D02*
X491015D01*
G01X489115Y37900D02*
X489715Y38500D01*
G01X489115Y35644D02*
Y37900D01*
G01X487871Y34400D02*
X489115Y35644D01*
G01X480200Y34400D02*
X487871D01*
G01X494100Y257200D02*
X497000Y260100D01*
G01X491300Y257200D02*
X494100D01*
G01X489587Y258913D02*
X491300Y257200D01*
G01X494556Y256100D02*
X497456Y259000D01*
G01X490844Y256100D02*
X494556D01*
G01X489131Y257813D02*
X490844Y256100D01*
G01X495200Y38256D02*
Y35300D01*
G01X498556Y39400D02*
X496344D01*
G01X499800Y38156D02*
X498556Y39400D01*
G01X499800Y35200D02*
Y38156D01*
G01X500363Y34637D02*
X499800Y35200D01*
G01X501600Y34637D02*
X500363D01*
G01X502200Y35237D02*
X501600Y34637D01*
G01X502200Y38856D02*
Y35237D01*
G01X503144Y39800D02*
X502200Y38856D01*
G01X512500Y39800D02*
X503144D01*
G01X507180Y38700D02*
X512044D01*
G01X506690Y38210D02*
X507180Y38700D01*
G01X504890Y38210D02*
X506690D01*
G01X504400Y38700D02*
X504890Y38210D01*
G01X503600Y38700D02*
X504400D01*
G01X503300Y38400D02*
X503600Y38700D01*
G01X503300Y34781D02*
Y38400D01*
G01X502056Y33537D02*
X503300Y34781D01*
G01X499907Y33537D02*
X502056D01*
G01X498700Y34744D02*
X499907Y33537D01*
G01X498700Y37700D02*
Y34744D01*
G01X498100Y38300D02*
X498700Y37700D01*
G01X496800Y38300D02*
X498100D01*
G01X496300Y37800D02*
X496800Y38300D01*
G01X496300Y34844D02*
Y37800D01*
G01X506300Y250500D02*
X517900D01*
G01X505300Y251500D02*
X506300Y250500D01*
G01X505300Y254300D02*
Y251500D01*
G01X499500Y260100D02*
X505300Y254300D01*
G01X505844Y249400D02*
X518356D01*
G01X504200Y251044D02*
X505844Y249400D01*
G01X504200Y253844D02*
Y251044D01*
G01X499044Y259000D02*
X504200Y253844D01*
G01X497456Y259000D02*
X499044D01*
G01X497000Y260100D02*
X499500D01*
G01X515755Y27501D02*
Y36545D01*
G01X517676Y25580D02*
X515755Y27501D01*
G01X517676Y24000D02*
Y25580D01*
G01X518769Y22907D02*
X517676Y24000D01*
G01X516576Y23999D02*
X515484Y22907D01*
G01X516576Y25124D02*
Y23999D01*
G01X514655Y27045D02*
X516576Y25124D01*
G01X514655Y36089D02*
Y27045D01*
G01X515755Y36545D02*
X512500Y39800D01*
G01X512044Y38700D02*
X514655Y36089D01*
G01X520400Y258344D02*
X518900Y259844D01*
G01X520400Y257156D02*
Y258344D01*
G01X518900Y255656D02*
X520400Y257156D01*
G01X518900Y251500D02*
Y255656D01*
G01X517900Y250500D02*
X518900Y251500D01*
G01X521500Y258800D02*
X520000Y260300D01*
G01X521500Y256700D02*
Y258800D01*
G01X520000Y255200D02*
X521500Y256700D01*
G01X520000Y251044D02*
Y255200D01*
G01X518356Y249400D02*
X520000Y251044D01*
G01X518900Y261435D02*
X517846Y262489D01*
G01X518900Y259844D02*
Y261435D01*
G01X520000Y261358D02*
X521131Y262489D01*
G01X520000Y260300D02*
Y261358D01*
G01X626821Y191700D02*
X601608Y166487D01*
G01X627277Y190600D02*
X602064Y165387D01*
G01X639106Y191700D02*
X626821D01*
G01X639562Y190600D02*
X627277D01*
G01X649981Y202575D02*
X639106Y191700D01*
G01X650437Y201475D02*
X639562Y190600D01*
G01X651741Y202575D02*
X649981D01*
G01X654234Y200082D02*
X651741Y202575D01*
G01X655082Y200082D02*
X654234D01*
G01X656782Y201782D02*
X655082Y200082D01*
G01X656782Y202630D02*
Y201782D01*
G01X654289Y205123D02*
X656782Y202630D01*
G01X654289Y206883D02*
Y205123D01*
G01X657377Y209971D02*
X654289Y206883D01*
G01X673362Y209971D02*
X657377D01*
G01X651285Y201475D02*
X650437D01*
G01X653778Y198982D02*
X651285Y201475D01*
G01X655538Y198982D02*
X653778D01*
G01X657882Y201326D02*
X655538Y198982D01*
G01X657882Y203086D02*
Y201326D01*
G01X655389Y205579D02*
X657882Y203086D01*
G01X655389Y206427D02*
Y205579D01*
G01X657833Y208871D02*
X655389Y206427D01*
G01X673818Y208871D02*
X657833D01*
G01X674635Y211244D02*
X673362Y209971D01*
G01X674635Y211937D02*
Y211244D01*
G01X675908Y213210D02*
X674635Y211937D01*
G01X676601Y213210D02*
X675908D01*
G01X678352Y214961D02*
X676601Y213210D01*
G01X682047Y217100D02*
X673818Y208871D01*
G01X678352Y215654D02*
Y214961D01*
G01X679625Y216927D02*
X678352Y215654D01*
G01X680318Y216927D02*
X679625D01*
G01X681591Y218200D02*
X680318Y216927D01*
G01X685844Y218200D02*
X681591D01*
G01X688608Y220964D02*
X685844Y218200D01*
G01X688608Y223908D02*
Y220964D01*
G01X690600Y225900D02*
X688608Y223908D01*
G01X693388Y225900D02*
X690600D01*
G01X698268Y230780D02*
X693388Y225900D01*
G01X686300Y217100D02*
X682047D01*
G01X689708Y220508D02*
X686300Y217100D01*
G01X689708Y223452D02*
Y220508D01*
G01X691056Y224800D02*
X689708Y223452D01*
G01X693844Y224800D02*
X691056D01*
G01X702044Y233000D02*
X693844Y224800D01*
G01X698268Y231473D02*
Y230780D01*
G01X699540Y232745D02*
X698268Y231473D01*
G01X700233Y232745D02*
X699540D01*
G01X701588Y234100D02*
X700233Y232745D01*
G01X706144Y234100D02*
X701588D01*
G01X711267Y239223D02*
X706144Y234100D01*
G01X706600Y233000D02*
X702044D01*
G01X718200Y244600D02*
X706600Y233000D01*
G01X711267Y239916D02*
Y239223D01*
G01X712540Y241189D02*
X711267Y239916D01*
G01X713233Y241189D02*
X712540D01*
G01X714505Y242461D02*
X713233Y241189D01*
G01X714505Y243154D02*
Y242461D01*
G01X715778Y244427D02*
X714505Y243154D01*
G01X716471Y244427D02*
X715778D01*
G01X717744Y245700D02*
X716471Y244427D01*
G01X727364Y245700D02*
X717744D01*
G01X727656Y244600D02*
X718200D01*
G01X731563Y248094D02*
X727364Y245700D01*
G01X733091Y249291D02*
X731563Y248094D01*
G01X733095Y249294D02*
X733091Y249291D01*
G01X733926Y249945D02*
X733095Y249294D01*
G01X733927Y249945D02*
X733926D01*
G01X735269Y250995D02*
X733927Y249945D01*
G01X737000Y252726D02*
X735269Y250995D01*
G01X737000Y256044D02*
Y252726D01*
G01X736260Y256784D02*
X737000Y256044D01*
G01X736260Y261397D02*
Y256784D01*
G01X732178Y247178D02*
X727656Y244600D01*
G01X733770Y248424D02*
X732178Y247178D01*
G01X733774Y248427D02*
X733770Y248424D01*
G01X736000Y250170D02*
X733774Y248427D01*
G01X738100Y252270D02*
X736000Y250170D01*
G01X738100Y256500D02*
Y252270D01*
G01X737360Y257240D02*
X738100Y256500D01*
G01X737360Y261396D02*
Y257240D01*
G01X735168Y262489D02*
X736260Y261397D01*
G01X738453Y262489D02*
X737360Y261396D01*
G54D12*
G01X42850Y208010D02*
Y218231D01*
G01X60210Y190650D02*
X42850Y208010D01*
G01X44150Y208549D02*
X60749Y191950D01*
G01X44150Y218770D02*
Y208549D01*
G01X46600Y211204D02*
Y221100D01*
G01X60023Y197781D02*
X46600Y211204D01*
G01X47900Y211743D02*
Y221639D01*
G01X60562Y199081D02*
X47900Y211743D01*
G01X39000Y220100D02*
X37900Y219000D01*
G01X40981Y220100D02*
X39000D01*
G01X42850Y218231D02*
X40981Y220100D01*
G01X41520Y221400D02*
X44150Y218770D01*
G01X39000Y221400D02*
X41520D01*
G01X37900Y222500D02*
X39000Y221400D01*
G01X50350Y225550D02*
X41800Y234100D01*
G01X39200Y227300D02*
X37900Y226000D01*
G01X40400Y227300D02*
X39200D01*
G01X46600Y221100D02*
X40400Y227300D01*
G01X38800Y228600D02*
X37900Y229500D01*
G01X40939Y228600D02*
X38800D01*
G01X47900Y221639D02*
X40939Y228600D01*
G01X39000Y234100D02*
X37900Y233000D01*
G01X41800Y234100D02*
X39000D01*
G01X39100Y235400D02*
X38000Y236500D01*
G01X42339Y235400D02*
X39100D01*
G01X51650Y226089D02*
X42339Y235400D01*
G01X41889Y249550D02*
X62000Y229439D01*
G01X41350Y248250D02*
X60700Y228900D01*
G01X38950Y241050D02*
X37900Y240000D01*
G01X41250Y241050D02*
X38950D01*
G01X54100Y228200D02*
X41250Y241050D01*
G01X39050Y242350D02*
X37900Y243500D01*
G01X41789Y242350D02*
X39050D01*
G01X55400Y228739D02*
X41789Y242350D01*
G01X38950Y249550D02*
X41889D01*
G01X38000Y250500D02*
X38950Y249550D01*
G01X39150Y248250D02*
X41350D01*
G01X37900Y247000D02*
X39150Y248250D01*
G01X45900Y255100D02*
X50500Y250500D01*
G01X39000Y255100D02*
X45900D01*
G01X37900Y254000D02*
X39000Y255100D01*
G01X46439Y256400D02*
X51800Y251039D01*
G01X39000Y256400D02*
X46439D01*
G01X37900Y257500D02*
X39000Y256400D01*
G01X56900Y181661D02*
X65711Y172850D01*
G01X56900Y183200D02*
Y181661D01*
G01X63440Y178148D02*
X64394Y177194D01*
G01X62252Y178148D02*
X63440D01*
G01X61297Y179103D02*
X62252Y178148D01*
G01X61297Y180291D02*
Y179103D01*
G01X60343Y181245D02*
X61297Y180291D01*
G01X59155Y181245D02*
X60343D01*
G01X58200Y182200D02*
X59155Y181245D01*
G01X58200Y183201D02*
Y182200D01*
G01X64403Y190650D02*
X60210D01*
G01X60749Y191950D02*
X64942D01*
G01X70919Y197781D02*
X60023D01*
G01X53295Y189075D02*
X51860Y187640D01*
G01X55325Y189075D02*
X53295D01*
G01X57500Y186900D02*
X55325Y189075D01*
G01X62849Y186900D02*
X57500D01*
G01X66752Y182997D02*
X62849Y186900D01*
G01X52895Y190375D02*
X51860Y191410D01*
G01X55864Y190375D02*
X52895D01*
G01X58039Y188200D02*
X55864Y190375D01*
G01X63388Y188200D02*
X58039D01*
G01X73288Y178300D02*
X63388Y188200D01*
G01X55720Y184380D02*
X56900Y183200D01*
G01X59379Y184380D02*
X58200Y183201D01*
G01X50350Y213000D02*
Y225550D01*
G01X60850Y202500D02*
X50350Y213000D01*
G01X71657Y202500D02*
X60850D01*
G01X61389Y203800D02*
X51650Y213539D01*
G01X72196Y203800D02*
X61389D01*
G01X71458Y199081D02*
X60562D01*
G01X70461Y206250D02*
X60030Y216681D01*
G01X51650Y213539D02*
Y226089D01*
G01X62000Y224796D02*
X78171Y208625D01*
G01X62000Y229439D02*
Y224796D01*
G01X60700Y224257D02*
X64752Y220205D01*
G01X60700Y228900D02*
Y224257D01*
G01X54100Y218572D02*
Y228200D01*
G01X55991Y216681D02*
X54100Y218572D01*
G01X60030Y216681D02*
X55991D01*
G01X55400Y219111D02*
Y228739D01*
G01X56530Y217981D02*
X55400Y219111D01*
G01X60569Y217981D02*
X56530D01*
G01X71000Y207550D02*
X60569Y217981D01*
G01X50500Y244404D02*
X64450Y230454D01*
G01X51800Y244943D02*
X65750Y230993D01*
G01X50500Y250500D02*
Y244404D01*
G01X51800Y251039D02*
Y244943D01*
G01X66752Y181809D02*
Y182997D01*
G01X67706Y180855D02*
X66752Y181809D01*
G01X68894Y180855D02*
X67706D01*
G01X72749Y177000D02*
X68894Y180855D01*
G01X76500Y177000D02*
X72749D01*
G01X79400Y179900D02*
X76500Y177000D01*
G01X75961Y178300D02*
X73288D01*
G01X78861Y181200D02*
X75961Y178300D01*
G01X91639Y181200D02*
X78861D01*
G01X65711Y172850D02*
X90311D01*
G01X66250Y174150D02*
X90850D01*
G01X64394Y176006D02*
X66250Y174150D01*
G01X64394Y177194D02*
Y176006D01*
G01X71403Y183650D02*
X64403Y190650D01*
G01X92654Y183650D02*
X71403D01*
G01X71942Y184950D02*
X93193D01*
G01X64942Y191950D02*
X71942Y184950D01*
G01X80207Y193950D02*
X71657Y202500D01*
G01X80746Y195250D02*
X72196Y203800D01*
G01X81300Y187400D02*
X70919Y197781D01*
G01X81839Y188700D02*
X71458Y199081D01*
G01X78171Y208625D02*
X102014D01*
G01X77632Y207325D02*
X101475D01*
G01X69991Y214966D02*
X77632Y207325D01*
G01X64450Y225811D02*
X79186Y211075D01*
G01X65750Y226350D02*
X79725Y212375D01*
G01X73211Y206250D02*
X70461D01*
G01X76861Y202600D02*
X73211Y206250D01*
G01X86479Y202600D02*
X76861D01*
G01X73750Y207550D02*
X71000D01*
G01X77400Y203900D02*
X73750Y207550D01*
G01X87018Y203900D02*
X77400D01*
G01X68803Y214966D02*
X69991D01*
G01X67849Y215920D02*
X68803Y214966D01*
G01X67849Y217108D02*
Y215920D01*
G01X66894Y218063D02*
X67849Y217108D01*
G01X65706Y218063D02*
X66894D01*
G01X64752Y219017D02*
X65706Y218063D01*
G01X64752Y220205D02*
Y219017D01*
G01X64450Y230454D02*
Y225811D01*
G01X65750Y230993D02*
Y226350D01*
G01X98979Y177325D02*
X92654Y183650D01*
G01X91100Y179900D02*
X79400D01*
G01X94328Y176672D02*
X91100Y179900D01*
G01X94328Y175484D02*
Y176672D01*
G01X95282Y174530D02*
X94328Y175484D01*
G01X99050Y173789D02*
X91639Y181200D01*
G01X90311Y172850D02*
X95530Y167631D01*
G01X90850Y174150D02*
X96830Y168170D01*
G01X93193Y184950D02*
X99518Y178625D01*
G01X87774Y193950D02*
X80207D01*
G01X88614Y193110D02*
X87774Y193950D01*
G01X89964Y193110D02*
X88614D01*
G01X90804Y193950D02*
X89964Y193110D01*
G01X92154Y193950D02*
X90804D01*
G01X92994Y193110D02*
X92154Y193950D01*
G01X94344Y193110D02*
X92994D01*
G01X95184Y193950D02*
X94344Y193110D01*
G01X101946Y195250D02*
X80746D01*
G01X94208Y187400D02*
X81300D01*
G01X100108Y181500D02*
X94208Y187400D01*
G01X94747Y188700D02*
X81839D01*
G01X79186Y211075D02*
X103807D01*
G01X79725Y212375D02*
X104346D01*
G01X88578Y200501D02*
X86479Y202600D01*
G01X100160Y200501D02*
X88578D01*
G01X89117Y201801D02*
X87018Y203900D01*
G01X100699Y201801D02*
X89117D01*
G01X108639Y149100D02*
X110100Y150561D01*
G01X106600Y149100D02*
X108639D01*
G01X95530Y160170D02*
X106600Y149100D01*
G01X108800Y151100D02*
Y154889D01*
G01X108100Y150400D02*
X108800Y151100D01*
G01X107139Y150400D02*
X108100D01*
G01X96830Y160709D02*
X107139Y150400D01*
G01X104189Y166689D02*
X108500Y171000D01*
G01X104189Y163310D02*
Y166689D01*
G01X105591Y161908D02*
X104189Y163310D01*
G01X107303Y161908D02*
X105591D01*
G01X113484Y168090D02*
X107303Y161908D01*
G01X105489Y166150D02*
X109800Y170461D01*
G01X105489Y163849D02*
Y166150D01*
G01X106130Y163208D02*
X105489Y163849D01*
G01X106764Y163208D02*
X106130D01*
G01X112945Y169390D02*
X106764Y163208D01*
G01X95530Y167631D02*
Y160170D01*
G01X108800Y154889D02*
X110761Y156850D01*
G01X96830Y168170D02*
Y160709D01*
G01X110189Y177325D02*
X98979D01*
G01X99518Y178625D02*
X110728D01*
G01X126900Y181500D02*
X100108D01*
G01X96470Y174530D02*
X95282D01*
G01X97750Y173250D02*
X96470Y174530D01*
G01X97750Y170750D02*
Y173250D01*
G01X99500Y169000D02*
X97750Y170750D01*
G01X101425Y169000D02*
X99500D01*
G01X106000Y173575D02*
X101425Y169000D01*
G01X107925Y173575D02*
X106000D01*
G01X108500Y173000D02*
X107925Y173575D01*
G01X108500Y171000D02*
Y173000D01*
G01X99050Y171289D02*
Y173789D01*
G01X100039Y170300D02*
X99050Y171289D01*
G01X100886Y170300D02*
X100039D01*
G01X105461Y174875D02*
X100886Y170300D01*
G01X108464Y174875D02*
X105461D01*
G01X109800Y173539D02*
X108464Y174875D01*
G01X96534Y193950D02*
X95184D01*
G01X97374Y193110D02*
X96534Y193950D01*
G01X98724Y193110D02*
X97374D01*
G01X99564Y193950D02*
X98724Y193110D01*
G01X101407Y193950D02*
X99564D01*
G01X105304Y190053D02*
X101407Y193950D01*
G01X105304Y188866D02*
Y190053D01*
G01X106258Y187911D02*
X105304Y188866D01*
G01X107446Y187911D02*
X106258D01*
G01X108463Y186894D02*
X107446Y187911D01*
G01X110516Y186894D02*
X108463D01*
G01X109002Y188194D02*
X101946Y195250D01*
G01X123117Y188194D02*
X109002D01*
G01X100647Y182800D02*
X94747Y188700D01*
G01X126361Y182800D02*
X100647D01*
G01X105836Y194825D02*
X100160Y200501D01*
G01X125525Y194825D02*
X105836D01*
G01X106375Y196125D02*
X100699Y201801D01*
G01X124986Y196125D02*
X106375D01*
G01X107929Y199875D02*
X119849D01*
G01X105800Y202004D02*
X107929Y199875D01*
G01X105800Y204839D02*
Y202004D01*
G01X102014Y208625D02*
X105800Y204839D01*
G01X107390Y198575D02*
X120388D01*
G01X104500Y201465D02*
X107390Y198575D01*
G01X104500Y204300D02*
Y201465D01*
G01X101475Y207325D02*
X104500Y204300D01*
G01X103807Y211075D02*
X111682Y203200D01*
G01X104346Y212375D02*
X112221Y204500D01*
G01X117050Y151450D02*
X153789D01*
G01X112950Y155550D02*
X117050Y151450D01*
G01X110100Y150561D02*
Y154350D01*
G01X126714Y160800D02*
X110189Y177325D01*
G01X110728Y178625D02*
X127253Y162100D01*
G01X115604Y166605D02*
X114120Y168090D01*
G01X115605Y166605D02*
X115604D01*
G01X115605Y164395D02*
Y166605D01*
G01X117500Y162500D02*
X115605Y164395D01*
G01X119710Y162500D02*
X117500D01*
G01X122200Y160010D02*
X119710Y162500D01*
G01X122200Y157300D02*
Y160010D01*
G01X124300Y155200D02*
X122200Y157300D01*
G01X152039Y155200D02*
X124300D01*
G01X116905Y167144D02*
X114659Y169390D01*
G01X116905Y164934D02*
Y167144D01*
G01X118039Y163800D02*
X116905Y164934D01*
G01X120249Y163800D02*
X118039D01*
G01X123500Y160549D02*
X120249Y163800D01*
G01X123500Y157839D02*
Y160549D01*
G01X124839Y156500D02*
X123500Y157839D01*
G01X151500Y156500D02*
X124839D01*
G01X111300Y155550D02*
X112950D01*
G01X110100Y154350D02*
X111300Y155550D01*
G01X117589Y152750D02*
X153250D01*
G01X113489Y156850D02*
X117589Y152750D01*
G01X110761Y156850D02*
X113489D01*
G01X114120Y168090D02*
X113484D01*
G01X109800Y170461D02*
Y173539D01*
G01X114659Y169390D02*
X112945D01*
G01X111356Y186054D02*
X110516Y186894D01*
G01X112706Y186054D02*
X111356D01*
G01X113546Y186894D02*
X112706Y186054D01*
G01X114896Y186894D02*
X113546D01*
G01X115736Y186054D02*
X114896Y186894D01*
G01X117086Y186054D02*
X115736D01*
G01X117926Y186894D02*
X117086Y186054D01*
G01X119276Y186894D02*
X117926D01*
G01X120116Y186054D02*
X119276Y186894D01*
G01X121466Y186054D02*
X120116D01*
G01X122306Y186894D02*
X121466Y186054D01*
G01X123656Y186894D02*
X122306D01*
G01X135362Y198600D02*
X123656Y186894D01*
G01X134823Y199900D02*
X123117Y188194D01*
G01X134711Y205850D02*
X124986Y196125D01*
G01X119849Y199875D02*
X133624Y213650D01*
G01X123485Y201672D02*
X134163Y212350D01*
G01X123485Y200484D02*
Y201672D01*
G01X122531Y199530D02*
X123485Y200484D01*
G01X121343Y199530D02*
X122531D01*
G01X120388Y198575D02*
X121343Y199530D01*
G01X119709Y203200D02*
X131174Y214665D01*
G01X111682Y203200D02*
X119709D01*
G01X119170Y204500D02*
X129874Y215204D01*
G01X112221Y204500D02*
X119170D01*
G01X148300Y160800D02*
X126714D01*
G01X127253Y162100D02*
X147761D01*
G01X136400Y191000D02*
X126900Y181500D01*
G01X140100Y191000D02*
X136400D01*
G01X142600Y188500D02*
X140100Y191000D01*
G01X135861Y192300D02*
X126361Y182800D01*
G01X140639Y192300D02*
X135861D01*
G01X143139Y189800D02*
X140639Y192300D01*
G01X135250Y204550D02*
X125525Y194825D01*
G01X141900Y198600D02*
X135362D01*
G01X142439Y199900D02*
X134823D01*
G01X134163Y212350D02*
X153732D01*
G01X150632Y204550D02*
X135250D01*
G01X150093Y205850D02*
X134711D01*
G01X133624Y213650D02*
X154271D01*
G01X132608Y216100D02*
X223065D01*
G01X131174Y214666D02*
X132608Y216100D01*
G01X131174Y214665D02*
Y214666D01*
G01X132069Y217400D02*
X222526D01*
G01X129874Y215205D02*
X132069Y217400D01*
G01X129874Y215204D02*
Y215205D01*
G01X153789Y151450D02*
X157539Y155200D01*
G01X151000Y163500D02*
X148300Y160800D01*
G01X151000Y175361D02*
Y163500D01*
G01X149700Y164039D02*
Y175900D01*
G01X147761Y162100D02*
X149700Y164039D01*
G01X154750Y157911D02*
X152039Y155200D01*
G01X154750Y160920D02*
Y157911D01*
G01X155590Y161760D02*
X154750Y160920D01*
G01X155590Y163110D02*
Y161760D01*
G01X154750Y163950D02*
X155590Y163110D01*
G01X154750Y173807D02*
Y163950D01*
G01X153450Y158450D02*
X151500Y156500D01*
G01X153450Y174346D02*
Y158450D01*
G01X153250Y152750D02*
X157000Y156500D01*
G01X160339Y184700D02*
X151000Y175361D01*
G01X149700Y175900D02*
X159800Y186000D01*
G01X157143Y176200D02*
X154750Y173807D01*
G01X156604Y177500D02*
X153450Y174346D01*
G01X143450Y197050D02*
X141900Y198600D01*
G01X166934Y197050D02*
X143450D01*
G01X149500Y188500D02*
X142600D01*
G01X152000Y191000D02*
X149500Y188500D01*
G01X153900Y191000D02*
X152000D01*
G01X156400Y188500D02*
X153900Y191000D01*
G01X148961Y189800D02*
X143139D01*
G01X151461Y192300D02*
X148961Y189800D01*
G01X154439Y192300D02*
X151461D01*
G01X156939Y189800D02*
X154439Y192300D01*
G01X143989Y198350D02*
X142439Y199900D01*
G01X166395Y198350D02*
X143989D01*
G01X154271Y213650D02*
X156871Y211050D01*
G01X153732Y212350D02*
X156332Y209750D01*
G01X152082Y206000D02*
X150632Y204550D01*
G01X167500Y206000D02*
X152082D01*
G01X151543Y207300D02*
X150093Y205850D01*
G01X168039Y207300D02*
X151543D01*
G01X166539Y155200D02*
X174710Y163371D01*
G01X157539Y155200D02*
X166539D01*
G01X166000Y156500D02*
X174171Y164671D01*
G01X162800Y156500D02*
X166000D01*
G01X161960Y157340D02*
X162800Y156500D01*
G01X160610Y157340D02*
X161960D01*
G01X159770Y156500D02*
X160610Y157340D01*
G01X157000Y156500D02*
X159770D01*
G01X157961Y176200D02*
X157143D01*
G01X158500Y175661D02*
X157961Y176200D01*
G01X158500Y170500D02*
Y175661D01*
G01X160092Y168908D02*
X158500Y170500D01*
G01X162908Y168908D02*
X160092D01*
G01X164000Y170000D02*
X162908Y168908D01*
G01X164000Y174500D02*
Y170000D01*
G01X165175Y175675D02*
X164000Y174500D01*
G01X170014Y175675D02*
X165175D01*
G01X175039Y180700D02*
X170014Y175675D01*
G01X158500Y177500D02*
X156604D01*
G01X159800Y176200D02*
X158500Y177500D01*
G01X159800Y171039D02*
Y176200D01*
G01X160631Y170208D02*
X159800Y171039D01*
G01X162369Y170208D02*
X160631D01*
G01X162700Y170539D02*
X162369Y170208D01*
G01X162700Y175039D02*
Y170539D01*
G01X164636Y176975D02*
X162700Y175039D01*
G01X169475Y176975D02*
X164636D01*
G01X174500Y182000D02*
X169475Y176975D01*
G01X193361Y184700D02*
X160339D01*
G01X159800Y186000D02*
X180591D01*
G01X170134Y200250D02*
X166934Y197050D01*
G01X165639Y188500D02*
X156400D01*
G01X173414Y196275D02*
X165639Y188500D01*
G01X165100Y189800D02*
X156939D01*
G01X172875Y197575D02*
X165100Y189800D01*
G01X187754Y200250D02*
X170134D01*
G01X169595Y201550D02*
X166395Y198350D01*
G01X187215Y201550D02*
X169595D01*
G01X156871Y211050D02*
X172861D01*
G01X156332Y209750D02*
X173400D01*
G01X169500Y204000D02*
X167500Y206000D01*
G01X186200Y204000D02*
X169500D01*
G01X170039Y205300D02*
X168039Y207300D01*
G01X185661Y205300D02*
X170039D01*
G01X181710Y163371D02*
X191439Y173100D01*
G01X174710Y163371D02*
X181710D01*
G01X181171Y164671D02*
X190900Y174400D01*
G01X174171Y164671D02*
X181171D01*
G01X177366Y180700D02*
X175039D01*
G01X178500Y179566D02*
X177366Y180700D01*
G01X178500Y177461D02*
Y179566D01*
G01X179961Y176000D02*
X178500Y177461D01*
G01X182039Y176000D02*
X179961D01*
G01X184000Y177961D02*
X182039Y176000D01*
G01X184000Y180500D02*
Y177961D01*
G01X184450Y180950D02*
X184000Y180500D01*
G01X185750Y180950D02*
X184450D01*
G01X186700Y180000D02*
X185750Y180950D01*
G01X186700Y178961D02*
Y180000D01*
G01X188811Y176850D02*
X186700Y178961D01*
G01X177905Y182000D02*
X174500D01*
G01X179800Y180105D02*
X177905Y182000D01*
G01X179800Y178000D02*
Y180105D01*
G01X180500Y177300D02*
X179800Y178000D01*
G01X181500Y177300D02*
X180500D01*
G01X182700Y178500D02*
X181500Y177300D01*
G01X182700Y181039D02*
Y178500D01*
G01X183911Y182250D02*
X182700Y181039D01*
G01X186289Y182250D02*
X183911D01*
G01X188000Y180539D02*
X186289Y182250D01*
G01X185811Y186840D02*
X187161D01*
G01X184971Y186000D02*
X185811Y186840D01*
G01X183621Y186000D02*
X184971D01*
G01X182781Y186840D02*
X183621Y186000D01*
G01X181431Y186840D02*
X182781D01*
G01X180591Y186000D02*
X181431Y186840D01*
G01X216396Y196275D02*
X173414D01*
G01X215857Y197575D02*
X172875D01*
G01X172861Y211050D02*
X175461Y213650D01*
G01X176000Y212350D02*
X224619D01*
G01X173400Y209750D02*
X176000Y212350D01*
G01X190800Y208600D02*
X186200Y204000D01*
G01X190261Y209900D02*
X185661Y205300D01*
G01X175461Y213650D02*
X224080D01*
G01X195600Y55300D02*
X194700Y54400D01*
G01X195600Y57039D02*
Y55300D01*
G01X203861Y65300D02*
X195600Y57039D01*
G01X196900Y55200D02*
X197700Y54400D01*
G01X196900Y56500D02*
Y55200D01*
G01X204400Y64000D02*
X196900Y56500D01*
G01X192139Y176850D02*
X188811D01*
G01X194289Y179000D02*
X192139Y176850D01*
G01X201489Y179000D02*
X194289D01*
G01X202329Y178160D02*
X201489Y179000D01*
G01X188000Y179500D02*
Y180539D01*
G01X189350Y178150D02*
X188000Y179500D01*
G01X191600Y178150D02*
X189350D01*
G01X193750Y180300D02*
X191600Y178150D01*
G01X209700Y180300D02*
X193750D01*
G01X201339Y173100D02*
X202239Y174000D01*
G01X191439Y173100D02*
X201339D01*
G01X201700Y175300D02*
X209407D01*
G01X200800Y174400D02*
X201700Y175300D01*
G01X190900Y174400D02*
X200800D01*
G01X194788Y183273D02*
X193361Y184700D01*
G01X209012Y183273D02*
X194788D01*
G01X195327Y184573D02*
X208473D01*
G01X193900Y186000D02*
X195327Y184573D01*
G01X188001Y186000D02*
X193900D01*
G01X187161Y186840D02*
X188001Y186000D01*
G01X189304Y201800D02*
X187754Y200250D01*
G01X197665Y201800D02*
X189304D01*
G01X198505Y200960D02*
X197665Y201800D01*
G01X199855Y200960D02*
X198505D01*
G01X200695Y201800D02*
X199855Y200960D01*
G01X202045Y201800D02*
X200695D01*
G01X202885Y200960D02*
X202045Y201800D01*
G01X188765Y203100D02*
X187215Y201550D01*
G01X210400Y203100D02*
X188765D01*
G01X226173Y208600D02*
X190800D01*
G01X225634Y209900D02*
X190261D01*
G01X207700Y55900D02*
X208700Y54900D01*
G01X207700Y57150D02*
Y55900D01*
G01X210000Y59450D02*
X207700Y57150D01*
G01X224600Y47300D02*
X212450Y59450D01*
G01X206400Y56000D02*
X205300Y54900D01*
G01X206400Y57689D02*
Y56000D01*
G01X209461Y60750D02*
X206400Y57689D01*
G01X225139Y48600D02*
X212989Y60750D01*
G01X216600Y65300D02*
X203861D01*
G01X227950Y53950D02*
X216600Y65300D01*
G01X216061Y64000D02*
X204400D01*
G01X227411Y52650D02*
X216061Y64000D01*
G01X212450Y59450D02*
X210000D01*
G01X212989Y60750D02*
X209461D01*
G01X216239Y116900D02*
X258312D01*
G01X214289Y114950D02*
X216239Y116900D01*
G01X210438Y114950D02*
X214289D01*
G01X209259Y113771D02*
X210438Y114950D01*
G01X215700Y118200D02*
X257773D01*
G01X213750Y116250D02*
X215700Y118200D01*
G01X210439Y116250D02*
X213750D01*
G01X209259Y117430D02*
X210439Y116250D01*
G01X203679Y178160D02*
X202329D01*
G01X204519Y179000D02*
X203679Y178160D01*
G01X205869Y179000D02*
X204519D01*
G01X206709Y178160D02*
X205869Y179000D01*
G01X208059Y178160D02*
X206709D01*
G01X208899Y179000D02*
X208059Y178160D01*
G01X210239Y179000D02*
X208899D01*
G01X213869Y182630D02*
X210239Y179000D01*
G01X216880Y181620D02*
X215870Y182630D01*
G01X218540Y181620D02*
X216880D01*
G01X213330Y183930D02*
X209700Y180300D01*
G01X202239Y174000D02*
X223086D01*
G01X216817Y175300D02*
X218167D01*
G01X215977Y176140D02*
X216817Y175300D01*
G01X214627Y176140D02*
X215977D01*
G01X213787Y175300D02*
X214627Y176140D01*
G01X212437Y175300D02*
X213787D01*
G01X211597Y176140D02*
X212437Y175300D01*
G01X210247Y176140D02*
X211597D01*
G01X209407Y175300D02*
X210247Y176140D01*
G01X222589Y196850D02*
X209012Y183273D01*
G01X208473Y184573D02*
X222050Y198150D01*
G01X220721Y200600D02*
X216396Y196275D01*
G01X220182Y201900D02*
X215857Y197575D01*
G01X215870Y182630D02*
X213869D01*
G01X216409Y183930D02*
X213330D01*
G01X217419Y182920D02*
X216409Y183930D01*
G01X219079Y182920D02*
X217419D01*
G01X204235Y200960D02*
X202885D01*
G01X205075Y201800D02*
X204235Y200960D01*
G01X210939Y201800D02*
X205075D01*
G01X213989Y204850D02*
X210939Y201800D01*
G01X227727Y204850D02*
X213989D01*
G01X213450Y206150D02*
X210400Y203100D01*
G01X227188Y206150D02*
X213450D01*
G01X289272Y53950D02*
X227950D01*
G01X289811Y52650D02*
X227411D01*
G01X290939Y47300D02*
X224600D01*
G01X290400Y48600D02*
X225139D01*
G01X218542Y181618D02*
X218540Y181620D01*
G01X219619Y181618D02*
X218542D01*
G01X221500Y183499D02*
X219619Y181618D01*
G01X223086Y174000D02*
X236886Y187800D01*
G01X222547Y175300D02*
X236347Y189100D01*
G01X221197Y175300D02*
X222547D01*
G01X220357Y176140D02*
X221197Y175300D01*
G01X219007Y176140D02*
X220357D01*
G01X218167Y175300D02*
X219007Y176140D01*
G01X235316Y196850D02*
X222589D01*
G01X221500Y186000D02*
Y183499D01*
G01X220500Y187000D02*
X221500Y186000D01*
G01X220500Y189261D02*
Y187000D01*
G01X221139Y189900D02*
X220500Y189261D01*
G01X223600Y189900D02*
X221139D01*
G01X224500Y189000D02*
X223600Y189900D01*
G01X224500Y185500D02*
Y189000D01*
G01X226000Y184000D02*
X224500Y185500D01*
G01X227782Y184000D02*
X226000D01*
G01X237082Y193300D02*
X227782Y184000D01*
G01X219080Y182919D02*
X219079Y182920D01*
G01X220200Y184039D02*
X219080Y182919D01*
G01X220200Y185461D02*
Y184039D01*
G01X219200Y186461D02*
X220200Y185461D01*
G01X219200Y189800D02*
Y186461D01*
G01X220600Y191200D02*
X219200Y189800D01*
G01X224139Y191200D02*
X220600D01*
G01X225800Y189539D02*
X224139Y191200D01*
G01X225800Y186039D02*
Y189539D01*
G01X226539Y185300D02*
X225800Y186039D01*
G01X227243Y185300D02*
X226539D01*
G01X236543Y194600D02*
X227243Y185300D01*
G01X222050Y198150D02*
X234777D01*
G01X238602Y215725D02*
X227727Y204850D01*
G01X238063Y217025D02*
X227188Y206150D01*
G01X224619Y212350D02*
X237094Y224825D01*
G01X233762Y200600D02*
X220721D01*
G01X233223Y201900D02*
X220182D01*
G01X237048Y219475D02*
X226173Y208600D01*
G01X236509Y220775D02*
X225634Y209900D01*
G01X224080Y213650D02*
X236555Y226125D01*
G01X223065Y216100D02*
X235540Y228575D01*
G01X222526Y217400D02*
X235001Y229875D01*
G01X240993Y181693D02*
X239900Y180600D01*
G01X242784Y181693D02*
X240993D01*
G01X246216Y185125D02*
X242784Y181693D01*
G01X243191Y204725D02*
X235316Y196850D01*
G01X248880Y193300D02*
X237082D01*
G01X248341Y194600D02*
X236543D01*
G01X252501Y198760D02*
X248341Y194600D01*
G01X244650Y189550D02*
X250434D01*
G01X242900Y187800D02*
X244650Y189550D01*
G01X236886Y187800D02*
X242900D01*
G01X244111Y190850D02*
X249895D01*
G01X242361Y189100D02*
X244111Y190850D01*
G01X236347Y189100D02*
X242361D01*
G01X245677Y186425D02*
X270725D01*
G01X242245Y182993D02*
X245677Y186425D01*
G01X241119Y182993D02*
X242245D01*
G01X240119Y183993D02*
X241119Y182993D01*
G01X247566Y185125D02*
X246216D01*
G01X248406Y184285D02*
X247566Y185125D01*
G01X249756Y184285D02*
X248406D01*
G01X255436Y204725D02*
X243191D01*
G01X242652Y206025D02*
X255975D01*
G01X234777Y198150D02*
X242652Y206025D01*
G01X237861Y204699D02*
X233762Y200600D01*
G01X237861Y209680D02*
Y204699D01*
G01X239610Y211429D02*
X237861Y209680D01*
G01X240807Y211429D02*
X239610D01*
G01X243761Y208475D02*
X240807Y211429D01*
G01X257125Y208475D02*
X243761D01*
G01X236561Y205238D02*
X233223Y201900D01*
G01X236561Y210219D02*
Y205238D01*
G01X239071Y212729D02*
X236561Y210219D01*
G01X241346Y212729D02*
X239071D01*
G01X244300Y209775D02*
X241346Y212729D01*
G01X257664Y209775D02*
X244300D01*
G01X242198Y215725D02*
X238602D01*
G01X243038Y214885D02*
X242198Y215725D01*
G01X244388Y214885D02*
X243038D01*
G01X245228Y215725D02*
X244388Y214885D01*
G01X261436Y215725D02*
X245228D01*
G01X261975Y217025D02*
X238063D01*
G01X236555Y226125D02*
X275114D01*
G01X248044Y223985D02*
X249394D01*
G01X247204Y224825D02*
X248044Y223985D01*
G01X245854Y224825D02*
X247204D01*
G01X245014Y223985D02*
X245854Y224825D01*
G01X243664Y223985D02*
X245014D01*
G01X242824Y224825D02*
X243664Y223985D01*
G01X237094Y224825D02*
X242824D01*
G01X235540Y228575D02*
X276129D01*
G01X268100Y219475D02*
X237048D01*
G01X268639Y220775D02*
X236509D01*
G01X235001Y229875D02*
X276668D01*
G01X261200Y58600D02*
X262000Y57800D01*
G01X261200Y59499D02*
Y58600D01*
G01X259900Y58700D02*
X259000Y57800D01*
G01X259900Y60038D02*
Y58700D01*
G01X252600Y58800D02*
X253500Y57900D01*
G01X252600Y64343D02*
Y58800D01*
G01X251300Y58700D02*
X250500Y57900D01*
G01X251300Y64882D02*
Y58700D01*
G01X262850Y61149D02*
X261200Y59499D01*
G01X286988Y61149D02*
X262850D01*
G01X262311Y62449D02*
X259900Y60038D01*
G01X286449Y62449D02*
X262311D01*
G01X253655Y65398D02*
X252600Y64343D01*
G01X254843Y65398D02*
X253655D01*
G01X255797Y66352D02*
X254843Y65398D01*
G01X255797Y67540D02*
Y66352D01*
G01X257357Y69100D02*
X255797Y67540D01*
G01X276100Y69100D02*
X257357D01*
G01X256818Y70400D02*
X251300Y64882D01*
G01X275561Y70400D02*
X256818D01*
G01X258312Y116900D02*
X263712Y122300D01*
G01X257773Y118200D02*
X263173Y123600D01*
G01X263712Y122300D02*
X290032D01*
G01X263173Y123600D02*
X289493D01*
G01X253040Y197460D02*
X248880Y193300D01*
G01X298460Y197460D02*
X253040D01*
G01X254594Y193710D02*
X299010D01*
G01X250434Y189550D02*
X254594Y193710D01*
G01X254055Y195010D02*
X298471D01*
G01X249895Y190850D02*
X254055Y195010D01*
G01X250596Y185125D02*
X249756Y184285D01*
G01X271264Y185125D02*
X250596D01*
G01X258951Y201210D02*
X255436Y204725D01*
G01X297010Y201210D02*
X258951D01*
G01X259490Y202510D02*
X296471D01*
G01X255975Y206025D02*
X259490Y202510D01*
G01X260640Y204960D02*
X257125Y208475D01*
G01X296110Y204960D02*
X260640D01*
G01X261179Y206260D02*
X257664Y209775D01*
G01X295571Y206260D02*
X261179D01*
G01X297921Y198760D02*
X252501D01*
G01X267080Y210080D02*
X261436Y215725D01*
G01X268990Y210010D02*
X261975Y217025D01*
G01X262919Y223985D02*
X264269D01*
G01X262079Y224825D02*
X262919Y223985D01*
G01X260729Y224825D02*
X262079D01*
G01X259889Y223985D02*
X260729Y224825D01*
G01X258539Y223985D02*
X259889D01*
G01X257699Y224825D02*
X258539Y223985D01*
G01X250234Y224825D02*
X257699D01*
G01X249394Y223985D02*
X250234Y224825D01*
G01X292525Y85525D02*
X276100Y69100D01*
G01X291986Y86825D02*
X275561Y70400D01*
G01X271500Y187200D02*
X288676D01*
G01X270725Y186425D02*
X271500Y187200D01*
G01X272039Y185900D02*
X271264Y185125D01*
G01X289215Y185900D02*
X272039D01*
G01X268451Y208710D02*
X267080Y210080D01*
G01X295210Y208710D02*
X268451D01*
G01X294671Y210010D02*
X268990D01*
G01X275114Y226125D02*
X281789Y219450D01*
G01X279154Y220245D02*
X281249Y218150D01*
G01X279154Y220246D02*
Y220245D01*
G01X274575Y224825D02*
X279154Y220246D01*
G01X269489Y224825D02*
X274575D01*
G01X268649Y223985D02*
X269489Y224825D01*
G01X267299Y223985D02*
X268649D01*
G01X266459Y224825D02*
X267299Y223985D01*
G01X265109Y224825D02*
X266459D01*
G01X264269Y223985D02*
X265109Y224825D01*
G01X276129Y228575D02*
X282804Y221900D01*
G01X276668Y229875D02*
X283343Y223200D01*
G01X273975Y213600D02*
X268100Y219475D01*
G01X285539Y213600D02*
X273975D01*
G01X274514Y214900D02*
X268639Y220775D01*
G01X285000Y214900D02*
X274514D01*
G01X294424Y59102D02*
X289272Y53950D01*
G01X294424Y62663D02*
Y59102D01*
G01X295724Y58563D02*
X289811Y52650D01*
G01X300275Y56636D02*
X290939Y47300D01*
G01X298975Y57175D02*
X290400Y48600D01*
G01X302612Y70851D02*
X294424Y62663D01*
G01X297000Y71161D02*
X286988Y61149D01*
G01X295700Y71700D02*
X286449Y62449D01*
G01X296793Y85525D02*
X292525D01*
G01X296254Y86825D02*
X291986D01*
G01X290032Y122300D02*
X294939Y127207D01*
G01X293639Y128713D02*
X295351Y130425D01*
G01X293639Y127746D02*
Y128713D01*
G01X289493Y123600D02*
X293639Y127746D01*
G01X289689Y188213D02*
X295126D01*
G01X288676Y187200D02*
X289689Y188213D01*
G01X290228Y186913D02*
X289215Y185900D01*
G01X294587Y186913D02*
X290228D01*
G01X296500Y185000D02*
X294587Y186913D01*
G01X297461Y212800D02*
X294671Y210010D01*
G01X294254Y219450D02*
X298120Y223316D01*
G01X281789Y219450D02*
X294254D01*
G01X281249Y218150D02*
X294793D01*
G01X293439Y221900D02*
X295900Y224361D01*
G01X282804Y221900D02*
X293439D01*
G01X294600Y224900D02*
Y229839D01*
G01X292900Y223200D02*
X294600Y224900D01*
G01X283343Y223200D02*
X292900D01*
G01X286339Y214400D02*
X285539Y213600D01*
G01X295915Y214400D02*
X286339D01*
G01X285800Y215700D02*
X285000Y214900D01*
G01X295376Y215700D02*
X285800D01*
G01X294600Y229839D02*
X306561Y241800D01*
G01X295724Y62124D02*
Y58563D01*
G01X300275Y60175D02*
Y56636D01*
G01X298975Y60714D02*
Y57175D01*
G01X306547Y70851D02*
X302612D01*
G01X317246Y81550D02*
X306547Y70851D01*
G01X303151Y69551D02*
X295724Y62124D01*
G01X307086Y69551D02*
X303151D01*
G01X317785Y80250D02*
X307086Y69551D01*
G01X305100Y65000D02*
X300275Y60175D01*
G01X309339Y65000D02*
X305100D01*
G01X318839Y74500D02*
X309339Y65000D01*
G01X304561Y66300D02*
X298975Y60714D01*
G01X308800Y66300D02*
X304561D01*
G01X318300Y75800D02*
X308800Y66300D01*
G01X297000Y73700D02*
Y71161D01*
G01X299155Y75855D02*
X297000Y73700D01*
G01X295700Y74239D02*
Y71700D01*
G01X311700Y90239D02*
X295700Y74239D01*
G01X300343Y75855D02*
X299155D01*
G01X301297Y76809D02*
X300343Y75855D01*
G01X301297Y77997D02*
Y76809D01*
G01X302252Y78952D02*
X301297Y77997D01*
G01X303440Y78952D02*
X302252D01*
G01X304394Y79906D02*
X303440Y78952D01*
G01X304394Y81094D02*
Y79906D01*
G01X305349Y82049D02*
X304394Y81094D01*
G01X306537Y82049D02*
X305349D01*
G01X307491Y83003D02*
X306537Y82049D01*
G01X307491Y84191D02*
Y83003D01*
G01X313000Y89700D02*
X307491Y84191D01*
G01X299043Y87775D02*
X296793Y85525D01*
G01X300339Y87775D02*
X299043D01*
G01X306301Y93737D02*
X300339Y87775D01*
G01X298504Y89075D02*
X296254Y86825D01*
G01X299800Y89075D02*
X298504D01*
G01X305001Y94276D02*
X299800Y89075D01*
G01X306301Y97584D02*
Y93737D01*
G01X320897Y112180D02*
X306301Y97584D01*
G01X305001Y98123D02*
Y94276D01*
G01X319096Y112218D02*
X305001Y98123D01*
G01X299600Y131800D02*
Y136804D01*
G01X296925Y129125D02*
X299600Y131800D01*
G01X295890Y129125D02*
X296925D01*
G01X294939Y128174D02*
X295890Y129125D01*
G01X294939Y127207D02*
Y128174D01*
G01X298300Y132339D02*
Y137343D01*
G01X296386Y130425D02*
X298300Y132339D01*
G01X295351Y130425D02*
X296386D01*
G01X299600Y136804D02*
X319547Y156751D01*
G01X298300Y137343D02*
X318627Y157670D01*
G01X301200Y200200D02*
X298460Y197460D01*
G01X309800Y197500D02*
X312600Y200300D01*
G01X302800Y197500D02*
X309800D01*
G01X299010Y193710D02*
X302800Y197500D01*
G01X298471Y195010D02*
X302261Y198800D01*
G01X297039Y186300D02*
X312461D01*
G01X295126Y188213D02*
X297039Y186300D01*
G01X313000Y185000D02*
X296500D01*
G01X300300Y204500D02*
X297010Y201210D01*
G01X303500Y204500D02*
X300300D01*
G01X317467Y218467D02*
X303500Y204500D01*
G01X302961Y205800D02*
X316928Y219767D01*
G01X299761Y205800D02*
X302961D01*
G01X296471Y202510D02*
X299761Y205800D01*
G01X298000Y211500D02*
X295210Y208710D01*
G01X300889Y211500D02*
X298000D01*
G01X314689Y225300D02*
X300889Y211500D01*
G01X300350Y212800D02*
X297461D01*
G01X314150Y226600D02*
X300350Y212800D01*
G01X299150Y208000D02*
X296110Y204960D01*
G01X302000Y208000D02*
X299150D01*
G01X316100Y222100D02*
X302000Y208000D01*
G01X298611Y209300D02*
X295571Y206260D01*
G01X301461Y209300D02*
X298611D01*
G01X315561Y223400D02*
X301461Y209300D01*
G01X307539Y200200D02*
X301200D01*
G01X311439Y204100D02*
X307539Y200200D01*
G01X300661Y201500D02*
X297921Y198760D01*
G01X307000Y201500D02*
X300661D01*
G01X310900Y205400D02*
X307000Y201500D01*
G01X309261Y198800D02*
X312061Y201600D01*
G01X302261Y198800D02*
X309261D01*
G01X298120Y228055D02*
X304265Y234200D01*
G01X298120Y223316D02*
Y228055D01*
G01X299420Y227516D02*
X304804Y232900D01*
G01X299420Y222777D02*
Y227516D01*
G01X294793Y218150D02*
X299420Y222777D01*
G01X295900Y224361D02*
Y229300D01*
G01X302775Y221260D02*
X295915Y214400D01*
G01X302775Y225775D02*
Y221260D01*
G01X306000Y229000D02*
X302775Y225775D01*
G01X301475Y221799D02*
X295376Y215700D01*
G01X301475Y226314D02*
Y221799D01*
G01X305461Y230300D02*
X301475Y226314D01*
G01X304265Y234200D02*
X315561D01*
G01X304804Y232900D02*
X316100D01*
G01X307100Y240500D02*
X322496D01*
G01X295900Y229300D02*
X307100Y240500D01*
G01X306561Y241800D02*
X321957D01*
G01X317839Y229000D02*
X306000D01*
G01X317300Y230300D02*
X305461D01*
G01X324439Y74500D02*
X318839D01*
G01X339800Y89861D02*
X324439Y74500D01*
G01X321211Y81550D02*
X317246D01*
G01X326525Y86864D02*
X321211Y81550D01*
G01X321750Y80250D02*
X317785D01*
G01X327825Y86325D02*
X321750Y80250D01*
G01X323900Y75800D02*
X318300D01*
G01X338500Y90400D02*
X323900Y75800D01*
G01X313000Y91500D02*
Y89700D01*
G01X316600Y95100D02*
X313000Y91500D01*
G01X323738Y95100D02*
X316600D01*
G01X327925Y99287D02*
X323738Y95100D01*
G01X311700Y92039D02*
Y90239D01*
G01X316061Y96400D02*
X311700Y92039D01*
G01X323199Y96400D02*
X316061D01*
G01X326625Y99826D02*
X323199Y96400D01*
G01X320992Y112180D02*
X320897D01*
G01X319096Y113300D02*
Y112218D01*
G01X323678Y186100D02*
X324350D01*
G01X321978Y187800D02*
X323678Y186100D01*
G01X313961Y187800D02*
X321978D01*
G01X312461Y186300D02*
X313961Y187800D01*
G01X314500Y186500D02*
X313000Y185000D01*
G01X315850Y186500D02*
X314500D01*
G01X316690Y185660D02*
X315850Y186500D01*
G01X318040Y185660D02*
X316690D01*
G01X318880Y186500D02*
X318040Y185660D01*
G01X321439Y186500D02*
X318880D01*
G01X323139Y184800D02*
X321439Y186500D01*
G01X324350Y184800D02*
X323139D01*
G01X318939Y204100D02*
X311439D01*
G01X320064Y205225D02*
X318939Y204100D01*
G01X326125Y205225D02*
X320064D01*
G01X318400Y205400D02*
X310900D01*
G01X319525Y206525D02*
X318400Y205400D01*
G01X326125Y206525D02*
X319525D01*
G01X320000Y200300D02*
X323200D01*
G01X318700Y199000D02*
X320000Y200300D01*
G01X315000Y199000D02*
X318700D01*
G01X313700Y200300D02*
X315000Y199000D01*
G01X312600Y200300D02*
X313700D01*
G01X319461Y201600D02*
X323200D01*
G01X318161Y200300D02*
X319461Y201600D01*
G01X315539Y200300D02*
X318161D01*
G01X314239Y201600D02*
X315539Y200300D01*
G01X312061Y201600D02*
X314239D01*
G01X328363Y218467D02*
X317467D01*
G01X316928Y219767D02*
X326767D01*
G01X321539Y225300D02*
X314689D01*
G01X329897Y233658D02*
X321539Y225300D01*
G01X321000Y226600D02*
X314150D01*
G01X328945Y234545D02*
X321000Y226600D01*
G01X322900Y222100D02*
X316100D01*
G01X324100Y223300D02*
X322900Y222100D01*
G01X335246Y223300D02*
X324100D01*
G01X322361Y223400D02*
X315561D01*
G01X323561Y224600D02*
X322361Y223400D01*
G01X335785Y224600D02*
X323561D01*
G01X316980Y236720D02*
X316000Y237700D01*
G01X316980Y235619D02*
Y236720D01*
G01X315561Y234200D02*
X316980Y235619D01*
G01X318280Y236880D02*
X319100Y237700D01*
G01X318280Y235080D02*
Y236880D01*
G01X316100Y232900D02*
X318280Y235080D01*
G01X324396Y242400D02*
X354800D01*
G01X322496Y240500D02*
X324396Y242400D01*
G01X323857Y243700D02*
X355339D01*
G01X321957Y241800D02*
X323857Y243700D01*
G01X324425Y235586D02*
X317839Y229000D01*
G01X324425Y237125D02*
Y235586D01*
G01X325900Y238600D02*
X324425Y237125D01*
G01X323125Y236125D02*
X317300Y230300D01*
G01X323125Y237664D02*
Y236125D01*
G01X325361Y239900D02*
X323125Y237664D01*
G01X330039Y239900D02*
X325361D01*
G01X326525Y88451D02*
Y86864D01*
G01X329449Y91375D02*
X326525Y88451D01*
G01X327825Y87912D02*
Y86325D01*
G01X329988Y90075D02*
X327825Y87912D01*
G01X335352Y93900D02*
X331527Y90075D01*
G01X339800Y97139D02*
Y89861D01*
G01X330988Y91375D02*
X329449D01*
G01X334813Y95200D02*
X330988Y91375D01*
G01X336246Y95200D02*
X334813D01*
G01X336750Y95704D02*
X336246Y95200D01*
G01X331527Y90075D02*
X329988D01*
G01X336350Y93900D02*
X335352D01*
G01X336750Y93500D02*
X336350Y93900D01*
G01X336753Y100186D02*
X339800Y97139D01*
G01X336753Y110714D02*
Y100186D01*
G01X338500Y96600D02*
Y90400D01*
G01X335453Y99647D02*
X338500Y96600D01*
G01X335453Y111253D02*
Y99647D01*
G01X327925Y101925D02*
Y99287D01*
G01X330500Y104500D02*
X327925Y101925D01*
G01X332506Y104500D02*
X330500D01*
G01X333313Y103693D02*
X332506Y104500D01*
G01X326625Y102464D02*
Y99826D01*
G01X329961Y105800D02*
X326625Y102464D01*
G01X342139Y116100D02*
X336753Y110714D01*
G01X341600Y117400D02*
X335453Y111253D01*
G01X332566Y105800D02*
X329961D01*
G01X333434Y106668D02*
X332566Y105800D01*
G01X328510Y218320D02*
X328363Y218467D01*
G01X326767Y219767D02*
X327024Y220024D01*
G01X340646Y217900D02*
X335246Y223300D01*
G01X342400Y217900D02*
X340646D01*
G01X341185Y219200D02*
X335785Y224600D01*
G01X337300Y226500D02*
Y230800D01*
G01X343500Y220300D02*
X337300Y226500D01*
G01X338600Y227039D02*
Y231339D01*
G01X344039Y221600D02*
X338600Y227039D01*
G01X331142Y233658D02*
X329897D01*
G01X328945Y235846D02*
Y234545D01*
G01X329500Y238600D02*
X325900D01*
G01X337300Y230800D02*
X329500Y238600D01*
G01X338600Y231339D02*
X330039Y239900D01*
G01X345659Y116100D02*
X342139D01*
G01X346596Y115163D02*
X345659Y116100D01*
G01X345833Y117400D02*
X341600D01*
G01X346596Y118163D02*
X345833Y117400D01*
G01X342400Y219200D02*
X341185D01*
G01X346200Y220300D02*
X343500D01*
G01X347050Y219450D02*
X346200Y220300D01*
G01X352600Y219450D02*
X347050D01*
G01X346739Y221600D02*
X344039D01*
G01X347589Y220750D02*
X346739Y221600D01*
G01X352600Y220750D02*
X347589D01*
G01X354800Y242400D02*
X361227Y235973D01*
G01X355339Y243700D02*
X362527Y236512D01*
G01X361227Y235973D02*
Y227500D01*
G01X362527Y236512D02*
Y227500D01*
G54D13*
G01X428984Y206024D02*
X426271D01*
G01X430510Y207550D02*
X428984Y206024D01*
G01X433216Y207550D02*
X430510D01*
G01X434742Y206024D02*
X433216Y207550D01*
G01X428300Y207674D02*
X426271D01*
G01X429826Y209200D02*
X428300Y207674D01*
G01X433900Y209200D02*
X429826D01*
G01X423500Y212200D02*
X425600Y214300D01*
G01X426284Y212650D02*
X424667Y211033D01*
G01X428534Y212650D02*
X426284D01*
G01X429424Y211760D02*
X428534Y212650D01*
G01X431674Y211760D02*
X429424D01*
G01X432564Y212650D02*
X431674Y211760D01*
G01X441015Y212650D02*
X432564D01*
G01X432645Y201911D02*
X449145D01*
G01X429884Y199150D02*
X432645Y201911D01*
G01X428450Y199150D02*
X429884D01*
G01X429200Y200800D02*
X428450D01*
G01X431961Y203561D02*
X429200Y200800D01*
G01X448461Y203561D02*
X431961D01*
G01X425600Y214300D02*
X466100D01*
G01X425069Y217050D02*
X421717Y213698D01*
G01X467725Y217050D02*
X425069D01*
G01X424385Y218700D02*
X437580D01*
G01X421300Y215615D02*
X424385Y218700D01*
G01X438958Y206024D02*
X434742D01*
G01X440184Y207250D02*
X438958Y206024D01*
G01X442116Y207250D02*
X440184D01*
G01X443316Y206050D02*
X442116Y207250D01*
G01X446784Y206050D02*
X443316D01*
G01X447984Y207250D02*
X446784Y206050D01*
G01X461316Y207250D02*
X447984D01*
G01X435426Y207674D02*
X433900Y209200D01*
G01X438274Y207674D02*
X435426D01*
G01X439500Y208900D02*
X438274Y207674D01*
G01X442800Y208900D02*
X439500D01*
G01X444000Y207700D02*
X442800Y208900D01*
G01X446100Y207700D02*
X444000D01*
G01X447300Y208900D02*
X446100Y207700D01*
G01X462000Y208900D02*
X447300D01*
G01X441905Y211760D02*
X441015Y212650D01*
G01X444155Y211760D02*
X441905D01*
G01X445045Y212650D02*
X444155Y211760D01*
G01X447295Y212650D02*
X445045D01*
G01X448185Y211760D02*
X447295Y212650D01*
G01X450435Y211760D02*
X448185D01*
G01X449800Y204900D02*
X448461Y203561D01*
G01X447890Y218700D02*
X468409D01*
G01X447000Y219590D02*
X447890Y218700D01*
G01X444750Y219590D02*
X447000D01*
G01X443860Y218700D02*
X444750Y219590D01*
G01X441610Y218700D02*
X443860D01*
G01X440720Y219590D02*
X441610Y218700D01*
G01X438470Y219590D02*
X440720D01*
G01X437580Y218700D02*
X438470Y219590D01*
G01X467467Y201099D02*
X461316Y207250D01*
G01X468151Y202749D02*
X462000Y208900D01*
G01X451325Y212650D02*
X450435Y211760D01*
G01X453575Y212650D02*
X451325D01*
G01X454465Y211760D02*
X453575Y212650D01*
G01X456715Y211760D02*
X454465D01*
G01X457605Y212650D02*
X456715Y211760D01*
G01X465416Y212650D02*
X457605D01*
G01X459550Y203250D02*
X466150Y196650D01*
G01X450484Y203250D02*
X459550D01*
G01X449145Y201911D02*
X450484Y203250D01*
G01X460234Y204900D02*
X449800D01*
G01X466834Y198300D02*
X460234Y204900D01*
G01X466150Y196650D02*
X563283D01*
G01X535523Y201099D02*
X467467D01*
G01X481971Y202749D02*
X468151D01*
G01X473251Y207149D02*
X480031D01*
G01X466100Y214300D02*
X473251Y207149D01*
G01X467007Y211059D02*
X465416Y212650D01*
G01X467007Y209800D02*
Y211059D01*
G01X468598Y208209D02*
X467007Y209800D01*
G01X469857Y208209D02*
X468598D01*
G01X472567Y205499D02*
X469857Y208209D01*
G01X480715Y205499D02*
X472567D01*
G01X473800Y210975D02*
X467725Y217050D01*
G01X508209Y210975D02*
X473800D01*
G01X474484Y212625D02*
X483924D01*
G01X468409Y218700D02*
X474484Y212625D01*
G01X562599Y198300D02*
X466834D01*
G01X482922Y203700D02*
X481971Y202749D01*
G01X484300Y203700D02*
X482922D01*
G01X485251Y202749D02*
X484300Y203700D01*
G01X500749Y202749D02*
X485251D01*
G01X495305Y208225D02*
X496381Y207149D01*
G01X490407Y208225D02*
X495305D01*
G01X489331Y207149D02*
X490407Y208225D01*
G01X487081Y207149D02*
X489331D01*
G01X486005Y208225D02*
X487081Y207149D01*
G01X481107Y208225D02*
X486005D01*
G01X480031Y207149D02*
X481107Y208225D01*
G01X481791Y206575D02*
X480715Y205499D01*
G01X485321Y206575D02*
X481791D01*
G01X486397Y205499D02*
X485321Y206575D01*
G01X490015Y205499D02*
X486397D01*
G01X491091Y206575D02*
X490015Y205499D01*
G01X494621Y206575D02*
X491091D01*
G01X495697Y205499D02*
X494621Y206575D01*
G01X494234Y212625D02*
X507525D01*
G01X493344Y213515D02*
X494234Y212625D01*
G01X490204D02*
X491094Y213515D01*
G01X487954Y212625D02*
X490204D01*
G01X487064Y213515D02*
X487954Y212625D01*
G01X483924D02*
X484814Y213515D01*
G01X491094D02*
X493344D01*
G01X484814D02*
X487064D01*
G01X501639Y203639D02*
X500749Y202749D01*
G01X502961Y203639D02*
X501639D01*
G01X503851Y202749D02*
X502961Y203639D01*
G01X514849Y202749D02*
X503851D01*
G01X505681Y207149D02*
X512015D01*
G01X504605Y208225D02*
X505681Y207149D01*
G01X499707Y208225D02*
X504605D01*
G01X498631Y207149D02*
X499707Y208225D01*
G01X496381Y207149D02*
X498631D01*
G01X499315Y205499D02*
X495697D01*
G01X500391Y206575D02*
X499315Y205499D01*
G01X503921Y206575D02*
X500391D01*
G01X504997Y205499D02*
X503921Y206575D01*
G01X512699Y205499D02*
X504997D01*
G01X509709Y212475D02*
X508209Y210975D01*
G01X557357Y212475D02*
X509709D01*
G01X507525Y212625D02*
X509025Y214125D01*
G01D02*
X556673D01*
G01X515739Y203639D02*
X514849Y202749D01*
G01X517861Y203639D02*
X515739D01*
G01X518751Y202749D02*
X517861Y203639D01*
G01X520949Y202749D02*
X518751D01*
G01X521839Y203639D02*
X520949Y202749D01*
G01X523961Y203639D02*
X521839D01*
G01X524851Y202749D02*
X523961Y203639D01*
G01X534839Y202749D02*
X524851D01*
G01X524177Y209450D02*
X527150D01*
G01X522766Y208039D02*
X524177Y209450D01*
G01X519995Y208039D02*
X522766D01*
G01X518309Y209725D02*
X519995Y208039D01*
G01X514591Y209725D02*
X518309D01*
G01X512015Y207149D02*
X514591Y209725D01*
G01X515275Y208075D02*
X512699Y205499D01*
G01X517625Y208075D02*
X515275D01*
G01X519311Y206389D02*
X517625Y208075D01*
G01X523450Y206389D02*
X519311D01*
G01X524861Y207800D02*
X523450Y206389D01*
G01X526466Y207800D02*
X524861D01*
G01X537774Y203350D02*
X535523Y201099D01*
G01X541000Y203350D02*
X537774D01*
G01X543251Y201099D02*
X541000Y203350D01*
G01X537090Y205000D02*
X534839Y202749D01*
G01X541684Y205000D02*
X537090D01*
G01X532725Y209725D02*
X543183D01*
G01X531039Y208039D02*
X532725Y209725D01*
G01X528561Y208039D02*
X531039D01*
G01X527150Y209450D02*
X528561Y208039D01*
G01X527877Y206389D02*
X526466Y207800D01*
G01X531723Y206389D02*
X527877D01*
G01X533409Y208075D02*
X531723Y206389D01*
G01X542499Y208075D02*
X533409D01*
G01X561508Y201099D02*
X543251D01*
G01X543935Y202749D02*
X541684Y205000D01*
G01X560824Y202749D02*
X543935D01*
G01X545759Y207149D02*
X559000D01*
G01X543183Y209725D02*
X545759Y207149D01*
G01X545075Y205499D02*
X542499Y208075D01*
G01X559684Y205499D02*
X545075D01*
G01X556673Y214125D02*
X557423Y214875D01*
G01X563283Y196650D02*
X565383Y198750D01*
G01X564084Y203675D02*
X561508Y201099D01*
G01X572875Y203675D02*
X564084D01*
G01X563400Y205325D02*
X560824Y202749D01*
G01X572191Y205325D02*
X563400D01*
G01X578016Y211150D02*
X572191Y205325D01*
G01X568515Y209725D02*
X574340Y215550D01*
G01X561576Y209725D02*
X568515D01*
G01X559000Y207149D02*
X561576Y209725D01*
G01X562260Y208075D02*
X559684Y205499D01*
G01X569199Y208075D02*
X562260D01*
G01X575024Y213900D02*
X569199Y208075D01*
G01X559073Y214191D02*
X557357Y212475D01*
G01X563789D02*
X562073Y214191D01*
G01X567375Y212475D02*
X563789D01*
G01X581915Y227015D02*
X567375Y212475D01*
G01X565383Y198750D02*
X586854D01*
G01X564699Y200400D02*
X562599Y198300D01*
G01X586170Y200400D02*
X564699D01*
G01X559073Y217500D02*
Y214191D01*
G01X559773Y218200D02*
X559073Y217500D01*
G01X561473Y218200D02*
X559773D01*
G01X562073Y217600D02*
X561473Y218200D01*
G01X562073Y214191D02*
Y217600D01*
G01X572099Y219533D02*
X573690Y221124D01*
G01X570840Y219533D02*
X572099D01*
G01X569249Y217942D02*
X570840Y219533D01*
G01X569249Y216683D02*
Y217942D01*
G01X566691Y214125D02*
X569249Y216683D01*
G01X564473Y214125D02*
X566691D01*
G01X563723Y214875D02*
X564473Y214125D01*
G01X563723Y218284D02*
Y214875D01*
G01X562157Y219850D02*
X563723Y218284D01*
G01X559089Y219850D02*
X562157D01*
G01X557423Y218184D02*
X559089Y219850D01*
G01X557423Y214875D02*
Y218184D01*
G01X578700Y209500D02*
X572875Y203675D01*
G01X588982Y209500D02*
X578700D01*
G01X580266Y211150D02*
X578016D01*
G01X581156Y212040D02*
X580266Y211150D01*
G01X583406Y212040D02*
X581156D01*
G01X584296Y211150D02*
X583406Y212040D01*
G01X588298Y211150D02*
X584296D01*
G01X586854Y198750D02*
X603964Y215860D01*
G01X603280Y217510D02*
X586170Y200400D01*
G01X587098Y219000D02*
X589924D01*
G01X584493Y221605D02*
X587098Y219000D01*
G01X580395Y221605D02*
X584493D01*
G01X578550Y219760D02*
X580395Y221605D01*
G01X578550Y216884D02*
Y219760D01*
G01X577216Y215550D02*
X578550Y216884D01*
G01X574340Y215550D02*
X577216D01*
G01X577900Y213900D02*
X575024D01*
G01X580200Y216200D02*
X577900Y213900D01*
G01X580200Y219076D02*
Y216200D01*
G01X581079Y219955D02*
X580200Y219076D01*
G01X583809Y219955D02*
X581079D01*
G01X586414Y217350D02*
X583809Y219955D01*
G01X590608Y217350D02*
X586414D01*
G01X582973Y227015D02*
X581915D01*
G01X587403Y222585D02*
X582973Y227015D01*
G01X589619Y222585D02*
X587403D01*
G01X583657Y228665D02*
X588087Y224235D01*
G01X581231Y228665D02*
X583657D01*
G01X576366Y223800D02*
X581231Y228665D01*
G01X575108Y223800D02*
X576366D01*
G01X573690Y222382D02*
X575108Y223800D01*
G01X573690Y221124D02*
Y222382D01*
G01X587429Y231471D02*
X591859Y227041D01*
G01X587429Y232529D02*
Y231471D01*
G01X589340Y234440D02*
X587429Y232529D01*
G01X585779Y233213D02*
X588656Y236090D01*
G01X585779Y230787D02*
Y233213D01*
G01X590209Y226357D02*
X585779Y230787D01*
G01X599742Y220260D02*
X588982Y209500D01*
G01X599058Y221910D02*
X588298Y211150D01*
G01X607773Y220260D02*
X599742D01*
G01X607089Y221910D02*
X599058D01*
G01X597591Y226667D02*
X603333D01*
G01X589924Y219000D02*
X597591Y226667D01*
G01X598275Y225017D02*
X590608Y217350D01*
G01X604017Y225017D02*
X598275D01*
G01X591859Y224825D02*
X589619Y222585D01*
G01X591859Y227041D02*
Y224825D01*
G01X590209Y225509D02*
Y226357D01*
G01X588935Y224235D02*
X590209Y225509D01*
G01X588087Y224235D02*
X588935D01*
G01X599725Y244275D02*
Y254970D01*
G01X605075Y238925D02*
X599725Y244275D01*
G01X601375Y244959D02*
X606725Y239609D01*
G01X590398Y234440D02*
X589340D01*
G01X594478Y230360D02*
X590398Y234440D01*
G01X596694Y230360D02*
X594478D01*
G01X598934Y232600D02*
X596694Y230360D01*
G01X598934Y234816D02*
Y232600D01*
G01X594854Y238896D02*
X598934Y234816D01*
G01X594854Y239954D02*
Y238896D01*
G01X598250Y243350D02*
X594854Y239954D01*
G01X598250Y255250D02*
Y243350D01*
G01X596600Y244034D02*
Y255934D01*
G01X593204Y240638D02*
X596600Y244034D01*
G01X593204Y238212D02*
Y240638D01*
G01X597284Y234132D02*
X593204Y238212D01*
G01X597284Y233284D02*
Y234132D01*
G01X596010Y232010D02*
X597284Y233284D01*
G01X595162Y232010D02*
X596010D01*
G01X591082Y236090D02*
X595162Y232010D01*
G01X588656Y236090D02*
X591082D01*
G01X599725Y254970D02*
X605305Y260550D01*
G01X601375Y254286D02*
Y244959D01*
G01X605989Y258900D02*
X601375Y254286D01*
G01X599748Y256748D02*
X598250Y255250D01*
G01X599781Y256748D02*
X599748D01*
G01X601786Y258753D02*
X599781Y256748D01*
G01X601786Y258786D02*
Y258753D01*
G01X605462Y262462D02*
X601786Y258786D01*
G01X600136Y259470D02*
X603812Y263146D01*
G01X600136Y259437D02*
Y259470D01*
G01X599097Y258398D02*
X600136Y259437D01*
G01X599064Y258398D02*
X599097D01*
G01X596600Y255934D02*
X599064Y258398D01*
G01X602600Y270600D02*
X604967Y272967D01*
G01X602600Y265512D02*
Y270600D01*
G01X603812Y264300D02*
X602600Y265512D01*
G01X612800Y225287D02*
X607773Y220260D01*
G01X612800Y245100D02*
Y225287D01*
G01X611150Y225971D02*
X607089Y221910D01*
G01X611150Y238136D02*
Y225971D01*
G01X605075Y228409D02*
Y238925D01*
G01X603333Y226667D02*
X605075Y228409D01*
G01X606725Y227725D02*
X604017Y225017D01*
G01X606725Y229975D02*
Y227725D01*
G01X618609Y224475D02*
X620200Y226066D01*
G01X617018Y221625D02*
X618609Y223216D01*
G01X615759Y221625D02*
X617018D01*
G01X614168Y220034D02*
X615759Y221625D01*
G01X614168Y218776D02*
Y220034D01*
G01X612577Y217185D02*
X614168Y218776D01*
G01X611319Y217185D02*
X612577D01*
G01X609994Y215860D02*
X611319Y217185D01*
G01X603964Y215860D02*
X609994D01*
G01X609310Y217510D02*
X603280D01*
G01X618550Y226750D02*
X609310Y217510D01*
G01X610260Y239026D02*
X611150Y238136D01*
G01X610260Y241276D02*
Y239026D01*
G01X611150Y242166D02*
X610260Y241276D01*
G01X611150Y244416D02*
Y242166D01*
G01X610066Y245500D02*
X611150Y244416D01*
G01X607615Y230865D02*
X606725Y229975D01*
G01X607615Y233115D02*
Y230865D01*
G01X606725Y234005D02*
X607615Y233115D01*
G01X606725Y239609D02*
Y234005D01*
G01X610750Y247150D02*
X612800Y245100D01*
G01X607750Y247150D02*
X610750D01*
G01X606562Y248338D02*
X607750Y247150D01*
G01X606562Y255462D02*
Y248338D01*
G01X606700Y255600D02*
X606562Y255462D01*
G01X607066Y245500D02*
X610066D01*
G01X604912Y247654D02*
X607066Y245500D01*
G01X604912Y253556D02*
Y247654D01*
G01X604074Y254394D02*
X604912Y253556D01*
G01X608000Y258900D02*
X605989D01*
G01X609761Y260661D02*
X608000Y258900D01*
G01X609937Y251929D02*
Y252106D01*
G01X611066Y250800D02*
X609937Y251929D01*
G01X616634Y250800D02*
X611066D01*
G01X620200Y247234D02*
X616634Y250800D01*
G01X615950Y249150D02*
X618550Y246550D01*
G01X610382Y249150D02*
X615950D01*
G01X608212Y251320D02*
X610382Y249150D01*
G01X608212Y253612D02*
Y251320D01*
G01X609500Y254900D02*
X608212Y253612D01*
G01X609039Y272889D02*
X609896D01*
G01X607271Y271121D02*
X609039Y272889D01*
G01X607271Y269229D02*
Y271121D01*
G01X608111Y268389D02*
X607271Y269229D01*
G01X608111Y261345D02*
Y268389D01*
G01X607316Y260550D02*
X608111Y261345D01*
G01X605305Y260550D02*
X607316D01*
G01X609761Y269373D02*
Y260661D01*
G01X608996Y270138D02*
X609761Y269373D01*
G01X608996Y270206D02*
Y270138D01*
G01X605462Y264984D02*
Y262462D01*
G01X604250Y266196D02*
X605462Y264984D01*
G01X604250Y269250D02*
Y266196D01*
G01X605100Y270100D02*
X604250Y269250D01*
G01X604967Y272967D02*
X605065D01*
G01X603812Y263146D02*
Y264300D01*
G01X620200Y226066D02*
Y233040D01*
G01X618609Y223216D02*
Y224475D01*
G01X618550Y246550D02*
Y226750D01*
G01X621090Y243882D02*
X620200Y244772D01*
G01X621090Y241632D02*
Y243882D01*
G01X620200Y240742D02*
X621090Y241632D01*
G01X620200Y237070D02*
Y240742D01*
G01X621090Y236180D02*
X620200Y237070D01*
G01X621090Y233930D02*
Y236180D01*
G01X620200Y233040D02*
X621090Y233930D01*
G01X620200Y244772D02*
Y247234D01*
M02*
